FILE_TYPE = MACRO_DRAWING;
SET COLOR_WIRE YELLOW;
SET COLOR_PROP ORANGE;
SET COLOR_DOT WHITE;
SET COLOR_ARC YELLOW;
SET COLOR_BODY GREEN;
SET COLOR_NOTE PURPLE;
SET PROP_DISPLAY VALUE;
SET PAGE_NUMBER P28;
FORCEADD OFFPAGE..2
R 2
(-8775 7350);
FORCEPROP 2 LAST $XR1 28 
J 0
(-9089 7350);
DISPLAY 0.638298 (-9089 7350);
PAINT MONO (-9089 7350);
FORCEPROP 2 LAST $XR0 82 
J 0
(-8999 7350);
DISPLAY 0.638298 (-8999 7350);
PAINT MONO (-8999 7350);
FORCEPROP 2 LAST CDS_LIB standard
J 0
(-8775 7350);
DISPLAY INVISIBLE (-8775 7350);
FORCEPROP 1 LAST OFFPAGE TRUE
J 2
(-9100 7225);
DISPLAY 0.872340 (-9100 7225);
PAINT GREEN (-9100 7225);
DISPLAY INVISIBLE (-9100 7225);
FORCEPROP 1 LAST COMMENT_BODY TRUE
J 2
(-8730 7255);
DISPLAY 0.872340 (-8730 7255);
PAINT GREEN (-8730 7255);
DISPLAY INVISIBLE (-8730 7255);
FORCEPROP 2 LAST PATH I1
J 0
(-8725 7425);
DISPLAY 0.680851 (-8725 7425);
DISPLAY INVISIBLE (-8725 7425);
FORCEADD OFFPAGE..2
R 2
(-8750 8375);
FORCEPROP 2 LAST $XR0 28 
J 0
(-8974 8375);
DISPLAY 0.638298 (-8974 8375);
PAINT MONO (-8974 8375);
FORCEPROP 2 LAST CDS_LIB standard
J 0
(-8750 8375);
DISPLAY INVISIBLE (-8750 8375);
FORCEPROP 1 LAST OFFPAGE TRUE
J 2
(-9075 8250);
DISPLAY 0.872340 (-9075 8250);
PAINT GREEN (-9075 8250);
DISPLAY INVISIBLE (-9075 8250);
FORCEPROP 1 LAST COMMENT_BODY TRUE
J 2
(-8705 8280);
DISPLAY 0.872340 (-8705 8280);
PAINT GREEN (-8705 8280);
DISPLAY INVISIBLE (-8705 8280);
FORCEPROP 2 LAST PATH I10
J 0
(-8950 8425);
DISPLAY 0.680851 (-8950 8425);
DISPLAY INVISIBLE (-8950 8425);
FORCEADD Q_RES..1
R 2
(-6375 10325);
FORCEPROP 1 LAST LOCATION R1205
J 2
(-6475 10325);
DISPLAY 0.489362 (-6475 10325);
PAINT SKYBLUE (-6475 10325);
FORCEPROP 0 LAST $SEC 1
J 0
(-6475 10375);
DISPLAY 0.680851 (-6475 10375);
PAINT MONO (-6475 10375);
DISPLAY INVISIBLE (-6475 10375);
FORCEPROP 0 LAST CDS_SEC 1
J 0
(-6475 10375);
DISPLAY 0.680851 (-6475 10375);
DISPLAY INVISIBLE (-6475 10375);
FORCEPROP 1 LASTPIN (-6275 10325) $PN 1
J 2
(-6287 10337);
DISPLAY 0.489362 (-6287 10337);
PAINT MONO (-6287 10337);
FORCEPROP 1 LASTPIN (-6475 10325) $PN 2
J 2
(-6437 10337);
DISPLAY 0.489362 (-6437 10337);
PAINT MONO (-6437 10337);
FORCEPROP 1 LAST VALUE 0
J 0
(-6275 10325);
DISPLAY 0.489362 (-6275 10325);
PAINT SKYBLUE (-6275 10325);
FORCEPROP 1 LAST PACK_TYPE 0402LF
J 2
(-6425 10250);
DISPLAY 0.489362 (-6425 10250);
PAINT SKYBLUE (-6425 10250);
DISPLAY INVISIBLE (-6425 10250);
FORCEPROP 1 LAST TOLERANCE 5%
J 2
(-6350 10250);
DISPLAY 0.489362 (-6350 10250);
PAINT SKYBLUE (-6350 10250);
DISPLAY INVISIBLE (-6350 10250);
FORCEPROP 1 LAST MATERIAL CHIP
J 2
(-6800 10250);
DISPLAY 0.489362 (-6800 10250);
PAINT SKYBLUE (-6800 10250);
DISPLAY INVISIBLE (-6800 10250);
FORCEPROP 1 LAST WATTAGE 1/16W
J 0
(-6775 10250);
DISPLAY 0.489362 (-6775 10250);
PAINT SKYBLUE (-6775 10250);
DISPLAY INVISIBLE (-6775 10250);
FORCEPROP 2 LAST CDS_LIB pure_quanta
J 0
(-6375 10325);
DISPLAY INVISIBLE (-6375 10325);
FORCEPROP 1 LAST PATH I100
J 2
(-6325 10475);
DISPLAY 0.978723 (-6325 10475);
PAINT WHITE (-6325 10475);
DISPLAY INVISIBLE (-6325 10475);
FORCEPROP 1 LAST PART_NUMBER CS00002JB13
J 2
(-6400 10375);
DISPLAY 0.489362 (-6400 10375);
PAINT SKYBLUE (-6400 10375);
DISPLAY INVISIBLE (-6400 10375);
FORCEADD OFFPAGE..2
R 2
(-6350 10625);
FORCEPROP 2 LAST $XR1 81 
J 0
(-6694 10625);
DISPLAY 0.638298 (-6694 10625);
PAINT MONO (-6694 10625);
FORCEPROP 2 LAST $XR0 28 
J 0
(-6604 10625);
DISPLAY 0.638298 (-6604 10625);
PAINT MONO (-6604 10625);
FORCEPROP 2 LAST CDS_LIB standard
J 0
(-6350 10625);
DISPLAY INVISIBLE (-6350 10625);
FORCEPROP 1 LAST OFFPAGE TRUE
J 2
(-6675 10500);
DISPLAY 0.872340 (-6675 10500);
PAINT GREEN (-6675 10500);
DISPLAY INVISIBLE (-6675 10500);
FORCEPROP 1 LAST COMMENT_BODY TRUE
J 2
(-6305 10530);
DISPLAY 0.872340 (-6305 10530);
PAINT GREEN (-6305 10530);
DISPLAY INVISIBLE (-6305 10530);
FORCEPROP 2 LAST PATH I101
J 0
(-6600 10675);
DISPLAY 0.680851 (-6600 10675);
DISPLAY INVISIBLE (-6600 10675);
FORCEADD UNIVERSAL_GND..1
(-5950 8325);
FORCEPROP 3 LASTPIN (-5950 8375) SIG_NAME GND\g
J 0
(-5940 8385);
DISPLAY 0.659574 (-5940 8385);
PAINT MONO (-5940 8385);
DISPLAY INVISIBLE (-5940 8385);
FORCEPROP 2 LAST CDS_LIB pure_quanta_power
J 0
(-5950 8325);
DISPLAY INVISIBLE (-5950 8325);
FORCEPROP 1 LAST HDL_POWER GND
J 1
(-5925 8250);
DISPLAY 0.872340 (-5925 8250);
PAINT GREEN (-5925 8250);
DISPLAY INVISIBLE (-5925 8250);
FORCEPROP 1 LAST PATH I102
J 0
(-5875 8325);
DISPLAY 0.872340 (-5875 8325);
PAINT AQUA (-5875 8325);
DISPLAY INVISIBLE (-5875 8325);
FORCEADD Q_XTAL_4P_13BI_24GND..1
(-5575 8650);
FORCEPROP 1 LAST LOCATION Y2
J 0
(-5725 9025);
DISPLAY 0.489362 (-5725 9025);
PAINT SKYBLUE (-5725 9025);
FORCEPROP 0 LAST $SEC 1
J 0
(-5725 9125);
DISPLAY 0.680851 (-5725 9125);
PAINT MONO (-5725 9125);
DISPLAY INVISIBLE (-5725 9125);
FORCEPROP 0 LAST CDS_SEC 1
J 0
(-5700 9150);
DISPLAY 1.021277 (-5700 9150);
DISPLAY INVISIBLE (-5700 9150);
FORCEPROP 0 LASTPIN (-5850 8525) $PN 2
J 2
(-5860 8535);
DISPLAY 0.489362 (-5860 8535);
PAINT MONO (-5860 8535);
FORCEPROP 0 LASTPIN (-5300 8525) $PN 4
J 0
(-5290 8535);
DISPLAY 0.489362 (-5290 8535);
PAINT MONO (-5290 8535);
FORCEPROP 0 LASTPIN (-5850 8725) $PN 1
J 2
(-5860 8735);
DISPLAY 0.489362 (-5860 8735);
PAINT MONO (-5860 8735);
FORCEPROP 0 LASTPIN (-5300 8725) $PN 3
J 0
(-5290 8735);
DISPLAY 0.489362 (-5290 8735);
PAINT MONO (-5290 8735);
FORCEPROP 2 LAST VALUE 48MHZ
J 0
(-5725 8975);
DISPLAY 0.489362 (-5725 8975);
PAINT SKYBLUE (-5725 8975);
FORCEPROP 2 LAST PART_TYPE SMLF
J 0
(-5725 9075);
DISPLAY 1.021277 (-5725 9075);
FORCEPROP 1 LAST MATERIAL MISC
J 0
(-5725 8829);
DISPLAY 0.489362 (-5725 8829);
PAINT SKYBLUE (-5725 8829);
FORCEPROP 1 LAST PIN_NAMES_ROTATE True
J 0
(-5575 8650);
DISPLAY 0.489362 (-5575 8650);
PAINT GREEN (-5575 8650);
DISPLAY INVISIBLE (-5575 8650);
FORCEPROP 1 LAST CDS_LMAN_SYM_OUTLINE -125,175,125,-175
J 0
(-5575 8650);
DISPLAY 0.468085 (-5575 8650);
PAINT GREEN (-5575 8650);
DISPLAY INVISIBLE (-5575 8650);
FORCEPROP 2 LAST CDS_LIB pure_quanta
J 0
(-5575 8650);
DISPLAY INVISIBLE (-5575 8650);
FORCEPROP 1 LAST PATH I103
J 0
(-5450 8475);
DISPLAY 0.723404 (-5450 8475);
PAINT GREEN (-5450 8475);
DISPLAY INVISIBLE (-5450 8475);
FORCEPROP 1 LAST PART_NUMBER BG648000076
J 0
(-5725 8900);
DISPLAY 0.489362 (-5725 8900);
PAINT SKYBLUE (-5725 8900);
DISPLAY INVISIBLE (-5725 8900);
FORCEADD Q_RES..1
(-5575 8125);
FORCEPROP 1 LAST LOCATION R432
J 0
(-5625 8175);
DISPLAY 0.489362 (-5625 8175);
PAINT SKYBLUE (-5625 8175);
FORCEPROP 0 LAST $SEC 1
J 0
(-5625 8275);
DISPLAY 0.680851 (-5625 8275);
PAINT MONO (-5625 8275);
DISPLAY INVISIBLE (-5625 8275);
FORCEPROP 0 LAST CDS_SEC 1
J 0
(-5625 8275);
DISPLAY 1.021277 (-5625 8275);
DISPLAY INVISIBLE (-5625 8275);
FORCEPROP 1 LASTPIN (-5675 8125) $PN 1
J 0
(-5663 8137);
DISPLAY 0.489362 (-5663 8137);
PAINT MONO (-5663 8137);
FORCEPROP 1 LASTPIN (-5475 8125) $PN 2
J 0
(-5513 8137);
DISPLAY 0.489362 (-5513 8137);
PAINT MONO (-5513 8137);
FORCEPROP 1 LAST WATTAGE 1/16W
J 2
(-5600 7975);
DISPLAY 0.489362 (-5600 7975);
PAINT SKYBLUE (-5600 7975);
FORCEPROP 1 LAST TOLERANCE 1%
J 0
(-5575 8025);
DISPLAY 0.489362 (-5575 8025);
PAINT SKYBLUE (-5575 8025);
FORCEPROP 1 LAST MATERIAL CHIP
J 0
(-5575 7975);
DISPLAY 0.489362 (-5575 7975);
PAINT SKYBLUE (-5575 7975);
FORCEPROP 1 LAST PACK_TYPE 0402LF
J 0
(-5325 7975);
DISPLAY 0.489362 (-5325 7975);
PAINT SKYBLUE (-5325 7975);
FORCEPROP 1 LAST VALUE 10M
J 2
(-5600 8025);
DISPLAY 0.489362 (-5600 8025);
PAINT SKYBLUE (-5600 8025);
FORCEPROP 2 LAST CDS_LIB pure_quanta
J 0
(-5575 8125);
DISPLAY INVISIBLE (-5575 8125);
FORCEPROP 1 LAST PATH I104
J 0
(-5625 8275);
DISPLAY 0.978723 (-5625 8275);
PAINT WHITE (-5625 8275);
DISPLAY INVISIBLE (-5625 8275);
FORCEPROP 1 LAST PART_NUMBER CS61002FB02
J 0
(-5625 8225);
DISPLAY 0.489362 (-5625 8225);
PAINT SKYBLUE (-5625 8225);
DISPLAY INVISIBLE (-5625 8225);
FORCEADD UNIVERSAL_GND..1
(-5150 8300);
FORCEPROP 3 LASTPIN (-5150 8350) SIG_NAME GND\g
J 0
(-5140 8360);
DISPLAY 0.659574 (-5140 8360);
PAINT MONO (-5140 8360);
DISPLAY INVISIBLE (-5140 8360);
FORCEPROP 2 LAST CDS_LIB pure_quanta_power
J 0
(-5150 8300);
DISPLAY INVISIBLE (-5150 8300);
FORCEPROP 1 LAST HDL_POWER GND
J 1
(-5125 8225);
DISPLAY 0.872340 (-5125 8225);
PAINT GREEN (-5125 8225);
DISPLAY INVISIBLE (-5125 8225);
FORCEPROP 1 LAST PATH I105
J 0
(-5075 8300);
DISPLAY 0.872340 (-5075 8300);
PAINT AQUA (-5075 8300);
DISPLAY INVISIBLE (-5075 8300);
FORCEADD UNIVERSAL_GND..1
(-4950 7600);
FORCEPROP 3 LASTPIN (-4950 7650) SIG_NAME GND\g
J 0
(-4940 7660);
DISPLAY 0.659574 (-4940 7660);
PAINT MONO (-4940 7660);
DISPLAY INVISIBLE (-4940 7660);
FORCEPROP 2 LAST CDS_LIB pure_quanta_power
J 0
(-4950 7600);
DISPLAY INVISIBLE (-4950 7600);
FORCEPROP 1 LAST HDL_POWER GND
J 1
(-4925 7525);
DISPLAY 0.872340 (-4925 7525);
PAINT GREEN (-4925 7525);
DISPLAY INVISIBLE (-4925 7525);
FORCEPROP 1 LAST PATH I106
J 0
(-4875 7600);
DISPLAY 0.872340 (-4875 7600);
PAINT AQUA (-4875 7600);
DISPLAY INVISIBLE (-4875 7600);
FORCEADD OFFPAGE..2
(-4550 9125);
FORCEPROP 2 LAST $XR0 28 
J 0
(-4361 9125);
DISPLAY 0.638298 (-4361 9125);
PAINT MONO (-4361 9125);
FORCEPROP 2 LAST CDS_LIB standard
J 0
(-4550 9125);
DISPLAY INVISIBLE (-4550 9125);
FORCEPROP 1 LAST OFFPAGE TRUE
J 0
(-4225 9000);
DISPLAY 0.872340 (-4225 9000);
PAINT GREEN (-4225 9000);
DISPLAY INVISIBLE (-4225 9000);
FORCEPROP 1 LAST COMMENT_BODY TRUE
J 0
(-4595 9030);
DISPLAY 0.872340 (-4595 9030);
PAINT GREEN (-4595 9030);
DISPLAY INVISIBLE (-4595 9030);
FORCEPROP 2 LAST PATH I108
J 0
(-4350 9175);
DISPLAY 0.680851 (-4350 9175);
DISPLAY INVISIBLE (-4350 9175);
FORCEADD OFFPAGE..2
(-4550 9175);
FORCEPROP 2 LAST $XR0 28 
J 0
(-4361 9175);
DISPLAY 0.638298 (-4361 9175);
PAINT MONO (-4361 9175);
FORCEPROP 2 LAST CDS_LIB standard
J 0
(-4550 9175);
DISPLAY INVISIBLE (-4550 9175);
FORCEPROP 1 LAST OFFPAGE TRUE
J 0
(-4225 9050);
DISPLAY 0.872340 (-4225 9050);
PAINT GREEN (-4225 9050);
DISPLAY INVISIBLE (-4225 9050);
FORCEPROP 1 LAST COMMENT_BODY TRUE
J 0
(-4595 9080);
DISPLAY 0.872340 (-4595 9080);
PAINT GREEN (-4595 9080);
DISPLAY INVISIBLE (-4595 9080);
FORCEPROP 2 LAST PATH I109
J 0
(-4350 9225);
DISPLAY 0.680851 (-4350 9225);
DISPLAY INVISIBLE (-4350 9225);
FORCEADD OFFPAGE..2
R 2
(-8750 8425);
FORCEPROP 2 LAST $XR0 28 
J 0
(-8974 8425);
DISPLAY 0.638298 (-8974 8425);
PAINT MONO (-8974 8425);
FORCEPROP 2 LAST CDS_LIB standard
J 0
(-8750 8425);
DISPLAY INVISIBLE (-8750 8425);
FORCEPROP 1 LAST OFFPAGE TRUE
J 2
(-9075 8300);
DISPLAY 0.872340 (-9075 8300);
PAINT GREEN (-9075 8300);
DISPLAY INVISIBLE (-9075 8300);
FORCEPROP 1 LAST COMMENT_BODY TRUE
J 2
(-8705 8330);
DISPLAY 0.872340 (-8705 8330);
PAINT GREEN (-8705 8330);
DISPLAY INVISIBLE (-8705 8330);
FORCEPROP 2 LAST PATH I11
J 0
(-8950 8475);
DISPLAY 0.680851 (-8950 8475);
DISPLAY INVISIBLE (-8950 8475);
FORCEADD OFFPAGE..1
(-7900 11775);
FORCEPROP 2 LAST $XR1 82 
J 0
(-8241 11775);
DISPLAY 0.638298 (-8241 11775);
PAINT MONO (-8241 11775);
FORCEPROP 2 LAST $XR0 28 
J 0
(-8151 11775);
DISPLAY 0.638298 (-8151 11775);
PAINT MONO (-8151 11775);
FORCEPROP 2 LAST CDS_LIB standard
J 0
(-7900 11775);
DISPLAY INVISIBLE (-7900 11775);
FORCEPROP 1 LAST OFFPAGE TRUE
J 0
(-7575 11650);
DISPLAY 0.872340 (-7575 11650);
PAINT GREEN (-7575 11650);
DISPLAY INVISIBLE (-7575 11650);
FORCEPROP 1 LAST COMMENT_BODY TRUE
J 0
(-7775 11675);
DISPLAY 0.872340 (-7775 11675);
PAINT GREEN (-7775 11675);
DISPLAY INVISIBLE (-7775 11675);
FORCEPROP 2 LAST PATH I112
J 0
(-8150 11825);
DISPLAY 0.680851 (-8150 11825);
DISPLAY INVISIBLE (-8150 11825);
FORCEADD OFFPAGE..5
R 2
(-7825 12225);
FORCEPROP 2 LAST $XR1 81 
J 0
(-7546 12225);
DISPLAY 0.638298 (-7546 12225);
PAINT MONO (-7546 12225);
FORCEPROP 2 LAST $XR0 28 
J 0
(-7636 12225);
DISPLAY 0.638298 (-7636 12225);
PAINT MONO (-7636 12225);
FORCEPROP 2 LAST BOM_COST SYS_CLOCK
J 2
(-8025 12325);
DISPLAY 0.808511 (-8025 12325);
DISPLAY INVISIBLE (-8025 12325);
FORCEPROP 2 LAST CDS_LIB standard
J 2
(-7825 12225);
DISPLAY INVISIBLE (-7825 12225);
FORCEPROP 2 LAST ROOM DB2000_2_NVME
J 2
(-8025 12275);
DISPLAY 0.808511 (-8025 12275);
PAINT RED (-8025 12275);
DISPLAY INVISIBLE (-8025 12275);
FORCEPROP 1 LAST OFFPAGE TRUE
J 2
(-8150 12100);
DISPLAY 0.872340 (-8150 12100);
PAINT GREEN (-8150 12100);
DISPLAY INVISIBLE (-8150 12100);
FORCEPROP 1 LAST COMMENT_BODY TRUE
J 2
(-7925 12150);
DISPLAY 0.872340 (-7925 12150);
PAINT GREEN (-7925 12150);
DISPLAY INVISIBLE (-7925 12150);
FORCEPROP 2 LAST PATH I113
J 0
(-7525 12275);
DISPLAY 0.680851 (-7525 12275);
DISPLAY INVISIBLE (-7525 12275);
FORCEADD OFFPAGE..5
R 2
(-7825 12325);
FORCEPROP 2 LAST $XR1 81 
J 0
(-7546 12325);
DISPLAY 0.638298 (-7546 12325);
PAINT MONO (-7546 12325);
FORCEPROP 2 LAST $XR0 28 
J 0
(-7636 12325);
DISPLAY 0.638298 (-7636 12325);
PAINT MONO (-7636 12325);
FORCEPROP 2 LAST CDS_LIB standard
J 0
(-7825 12325);
DISPLAY INVISIBLE (-7825 12325);
FORCEPROP 2 LAST BOM_COST SYS_CLOCK
J 2
(-8025 12425);
DISPLAY 0.808511 (-8025 12425);
DISPLAY INVISIBLE (-8025 12425);
FORCEPROP 2 LAST ROOM DB2000_2_NVME
J 2
(-8025 12375);
DISPLAY 0.808511 (-8025 12375);
PAINT RED (-8025 12375);
DISPLAY INVISIBLE (-8025 12375);
FORCEPROP 1 LAST OFFPAGE TRUE
J 2
(-8150 12200);
DISPLAY 0.872340 (-8150 12200);
PAINT GREEN (-8150 12200);
DISPLAY INVISIBLE (-8150 12200);
FORCEPROP 1 LAST COMMENT_BODY TRUE
J 2
(-7925 12250);
DISPLAY 0.872340 (-7925 12250);
PAINT GREEN (-7925 12250);
DISPLAY INVISIBLE (-7925 12250);
FORCEPROP 2 LAST PATH I114
J 0
(-7525 12375);
DISPLAY 0.680851 (-7525 12375);
DISPLAY INVISIBLE (-7525 12375);
FORCEADD OFFPAGE..2
(-7700 12825);
FORCEPROP 2 LAST $XR1 81 
J 0
(-7421 12825);
DISPLAY 0.638298 (-7421 12825);
PAINT MONO (-7421 12825);
FORCEPROP 2 LAST $XR0 28 
J 0
(-7511 12825);
DISPLAY 0.638298 (-7511 12825);
PAINT MONO (-7511 12825);
FORCEPROP 2 LAST CDS_LIB standard
J 0
(-7700 12825);
DISPLAY INVISIBLE (-7700 12825);
FORCEPROP 1 LAST OFFPAGE TRUE
J 0
(-7375 12700);
DISPLAY 0.872340 (-7375 12700);
PAINT GREEN (-7375 12700);
DISPLAY INVISIBLE (-7375 12700);
FORCEPROP 1 LAST COMMENT_BODY TRUE
J 0
(-7745 12730);
DISPLAY 0.872340 (-7745 12730);
PAINT GREEN (-7745 12730);
DISPLAY INVISIBLE (-7745 12730);
FORCEPROP 2 LAST PATH I115
J 0
(-7400 12875);
DISPLAY 0.680851 (-7400 12875);
DISPLAY INVISIBLE (-7400 12875);
FORCEADD OFFPAGE..2
(-7700 12875);
FORCEPROP 2 LAST $XR1 81 
J 0
(-7421 12875);
DISPLAY 0.638298 (-7421 12875);
PAINT MONO (-7421 12875);
FORCEPROP 2 LAST $XR0 28 
J 0
(-7511 12875);
DISPLAY 0.638298 (-7511 12875);
PAINT MONO (-7511 12875);
FORCEPROP 2 LAST CDS_LIB standard
J 2
(-7700 12875);
DISPLAY INVISIBLE (-7700 12875);
FORCEPROP 1 LAST OFFPAGE TRUE
J 0
(-7375 12750);
DISPLAY 0.872340 (-7375 12750);
PAINT GREEN (-7375 12750);
DISPLAY INVISIBLE (-7375 12750);
FORCEPROP 1 LAST COMMENT_BODY TRUE
J 0
(-7745 12780);
DISPLAY 0.872340 (-7745 12780);
PAINT GREEN (-7745 12780);
DISPLAY INVISIBLE (-7745 12780);
FORCEPROP 2 LAST PATH I116
J 0
(-7400 12925);
DISPLAY 0.680851 (-7400 12925);
DISPLAY INVISIBLE (-7400 12925);
FORCEADD OFFPAGE..2
R 2
(-7225 12625);
FORCEPROP 2 LAST $XR0 81 
J 0
(-7449 12625);
DISPLAY 0.638298 (-7449 12625);
PAINT MONO (-7449 12625);
FORCEPROP 2 LAST CDS_LIB standard
J 2
(-7225 12625);
DISPLAY INVISIBLE (-7225 12625);
FORCEPROP 1 LAST OFFPAGE TRUE
J 2
(-7550 12500);
DISPLAY 0.872340 (-7550 12500);
PAINT GREEN (-7550 12500);
DISPLAY INVISIBLE (-7550 12500);
FORCEPROP 1 LAST COMMENT_BODY TRUE
J 2
(-7180 12530);
DISPLAY 0.872340 (-7180 12530);
PAINT GREEN (-7180 12530);
DISPLAY INVISIBLE (-7180 12530);
FORCEPROP 2 LAST PATH I117
J 0
(-7475 12675);
DISPLAY 0.680851 (-7475 12675);
DISPLAY INVISIBLE (-7475 12675);
FORCEADD OFFPAGE..2
R 2
(-7225 12675);
FORCEPROP 2 LAST $XR0 81 
J 0
(-7449 12675);
DISPLAY 0.638298 (-7449 12675);
PAINT MONO (-7449 12675);
FORCEPROP 2 LAST CDS_LIB standard
J 2
(-7225 12675);
DISPLAY INVISIBLE (-7225 12675);
FORCEPROP 1 LAST OFFPAGE TRUE
J 2
(-7550 12550);
DISPLAY 0.872340 (-7550 12550);
PAINT GREEN (-7550 12550);
DISPLAY INVISIBLE (-7550 12550);
FORCEPROP 1 LAST COMMENT_BODY TRUE
J 2
(-7180 12580);
DISPLAY 0.872340 (-7180 12580);
PAINT GREEN (-7180 12580);
DISPLAY INVISIBLE (-7180 12580);
FORCEPROP 2 LAST PATH I118
J 0
(-7475 12725);
DISPLAY 0.680851 (-7475 12725);
DISPLAY INVISIBLE (-7475 12725);
FORCEADD OFFPAGE..3
R 2
(-7050 11275);
FORCEPROP 2 LAST $XR1 159 
J 0
(-7419 11275);
DISPLAY 0.638298 (-7419 11275);
PAINT MONO (-7419 11275);
FORCEPROP 2 LAST $XR0 28 
J 0
(-7299 11275);
DISPLAY 0.638298 (-7299 11275);
PAINT MONO (-7299 11275);
FORCEPROP 2 LAST CDS_LIB standard
J 0
(-7050 11275);
DISPLAY INVISIBLE (-7050 11275);
FORCEPROP 1 LAST OFFPAGE TRUE
J 2
(-7375 11150);
DISPLAY 0.872340 (-7375 11150);
PAINT GREEN (-7375 11150);
DISPLAY INVISIBLE (-7375 11150);
FORCEPROP 1 LAST COMMENT_BODY TRUE
J 2
(-7000 11175);
DISPLAY 0.872340 (-7000 11175);
PAINT PEACH (-7000 11175);
DISPLAY INVISIBLE (-7000 11175);
FORCEPROP 2 LAST PATH I119
J 0
(-7275 11325);
DISPLAY 0.680851 (-7275 11325);
DISPLAY INVISIBLE (-7275 11325);
FORCEADD OFFPAGE..2
R 2
(-8750 8275);
FORCEPROP 2 LAST $XR1 81 
J 0
(-9064 8275);
DISPLAY 0.638298 (-9064 8275);
PAINT MONO (-9064 8275);
FORCEPROP 2 LAST $XR0 28 
J 0
(-8974 8275);
DISPLAY 0.638298 (-8974 8275);
PAINT MONO (-8974 8275);
FORCEPROP 2 LAST CDS_LIB standard
J 0
(-8750 8275);
DISPLAY INVISIBLE (-8750 8275);
FORCEPROP 1 LAST OFFPAGE TRUE
J 2
(-9075 8150);
DISPLAY 0.872340 (-9075 8150);
PAINT GREEN (-9075 8150);
DISPLAY INVISIBLE (-9075 8150);
FORCEPROP 1 LAST COMMENT_BODY TRUE
J 2
(-8705 8180);
DISPLAY 0.872340 (-8705 8180);
PAINT GREEN (-8705 8180);
DISPLAY INVISIBLE (-8705 8180);
FORCEPROP 2 LAST PATH I12
J 0
(-8950 8325);
DISPLAY 0.680851 (-8950 8325);
DISPLAY INVISIBLE (-8950 8325);
FORCEADD OFFPAGE..3
R 2
(-7050 11175);
FORCEPROP 2 LAST $XR1 159 
J 0
(-7419 11175);
DISPLAY 0.638298 (-7419 11175);
PAINT MONO (-7419 11175);
FORCEPROP 2 LAST $XR0 28 
J 0
(-7299 11175);
DISPLAY 0.638298 (-7299 11175);
PAINT MONO (-7299 11175);
FORCEPROP 2 LAST CDS_LIB standard
J 0
(-7050 11175);
DISPLAY INVISIBLE (-7050 11175);
FORCEPROP 1 LAST OFFPAGE TRUE
J 2
(-7375 11050);
DISPLAY 0.872340 (-7375 11050);
PAINT GREEN (-7375 11050);
DISPLAY INVISIBLE (-7375 11050);
FORCEPROP 1 LAST COMMENT_BODY TRUE
J 2
(-7000 11075);
DISPLAY 0.872340 (-7000 11075);
PAINT PEACH (-7000 11075);
DISPLAY INVISIBLE (-7000 11075);
FORCEPROP 2 LAST PATH I120
J 0
(-7275 11225);
DISPLAY 0.680851 (-7275 11225);
DISPLAY INVISIBLE (-7275 11225);
FORCEADD OFFPAGE..2
R 2
(-7050 11225);
FORCEPROP 2 LAST $XR1 159 
J 0
(-7424 11225);
DISPLAY 0.638298 (-7424 11225);
PAINT MONO (-7424 11225);
FORCEPROP 2 LAST $XR0 28 
J 0
(-7304 11225);
DISPLAY 0.638298 (-7304 11225);
PAINT MONO (-7304 11225);
FORCEPROP 2 LAST CDS_LIB standard
J 2
(-7050 11225);
DISPLAY INVISIBLE (-7050 11225);
FORCEPROP 1 LAST OFFPAGE TRUE
J 2
(-7375 11100);
DISPLAY 0.872340 (-7375 11100);
PAINT GREEN (-7375 11100);
DISPLAY INVISIBLE (-7375 11100);
FORCEPROP 1 LAST COMMENT_BODY TRUE
J 2
(-7005 11130);
DISPLAY 0.872340 (-7005 11130);
PAINT GREEN (-7005 11130);
DISPLAY INVISIBLE (-7005 11130);
FORCEPROP 2 LAST PATH I124
J 0
(-7300 11275);
DISPLAY 0.680851 (-7300 11275);
DISPLAY INVISIBLE (-7300 11275);
FORCEADD OFFPAGE..2
R 2
(-7050 11325);
FORCEPROP 2 LAST $XR1 159 
J 0
(-7424 11325);
DISPLAY 0.638298 (-7424 11325);
PAINT MONO (-7424 11325);
FORCEPROP 2 LAST $XR0 28 
J 0
(-7304 11325);
DISPLAY 0.638298 (-7304 11325);
PAINT MONO (-7304 11325);
FORCEPROP 2 LAST CDS_LIB standard
J 2
(-7050 11325);
DISPLAY INVISIBLE (-7050 11325);
FORCEPROP 1 LAST OFFPAGE TRUE
J 2
(-7375 11200);
DISPLAY 0.872340 (-7375 11200);
PAINT GREEN (-7375 11200);
DISPLAY INVISIBLE (-7375 11200);
FORCEPROP 1 LAST COMMENT_BODY TRUE
J 2
(-7005 11230);
DISPLAY 0.872340 (-7005 11230);
PAINT GREEN (-7005 11230);
DISPLAY INVISIBLE (-7005 11230);
FORCEPROP 2 LAST PATH I125
J 0
(-7300 11375);
DISPLAY 0.680851 (-7300 11375);
DISPLAY INVISIBLE (-7300 11375);
FORCEADD OFFPAGE..4
R 2
(-6700 11575);
FORCEPROP 2 LAST $XR1 81 
J 0
(-7011 11575);
DISPLAY 0.638298 (-7011 11575);
PAINT MONO (-7011 11575);
FORCEPROP 2 LAST $XR0 28 
J 0
(-6921 11575);
DISPLAY 0.638298 (-6921 11575);
PAINT MONO (-6921 11575);
FORCEPROP 2 LAST CDS_LIB standard
J 0
(-6700 11575);
DISPLAY INVISIBLE (-6700 11575);
FORCEPROP 1 LAST OFFPAGE TRUE
J 2
(-7025 11450);
DISPLAY 0.872340 (-7025 11450);
PAINT GREEN (-7025 11450);
DISPLAY INVISIBLE (-7025 11450);
FORCEPROP 1 LAST COMMENT_BODY TRUE
J 2
(-6675 11475);
DISPLAY 0.872340 (-6675 11475);
PAINT GREEN (-6675 11475);
DISPLAY INVISIBLE (-6675 11475);
FORCEPROP 2 LAST PATH I126
J 0
(-6900 11625);
DISPLAY 0.680851 (-6900 11625);
DISPLAY INVISIBLE (-6900 11625);
FORCEADD OFFPAGE..1
(-6375 11925);
FORCEPROP 2 LAST $XR0 28 
J 0
(-6596 11925);
DISPLAY 0.638298 (-6596 11925);
PAINT MONO (-6596 11925);
FORCEPROP 2 LAST CDS_LIB standard
J 0
(-6375 11925);
DISPLAY INVISIBLE (-6375 11925);
FORCEPROP 1 LAST OFFPAGE TRUE
J 0
(-6050 11800);
DISPLAY 0.872340 (-6050 11800);
PAINT GREEN (-6050 11800);
DISPLAY INVISIBLE (-6050 11800);
FORCEPROP 1 LAST COMMENT_BODY TRUE
J 0
(-6250 11825);
DISPLAY 0.872340 (-6250 11825);
PAINT GREEN (-6250 11825);
DISPLAY INVISIBLE (-6250 11825);
FORCEPROP 2 LAST PATH I127
J 0
(-6575 11975);
DISPLAY 0.680851 (-6575 11975);
DISPLAY INVISIBLE (-6575 11975);
FORCEADD OFFPAGE..1
(-6375 11975);
FORCEPROP 2 LAST $XR0 28 
J 0
(-6596 11975);
DISPLAY 0.638298 (-6596 11975);
PAINT MONO (-6596 11975);
FORCEPROP 2 LAST CDS_LIB standard
J 0
(-6375 11975);
DISPLAY INVISIBLE (-6375 11975);
FORCEPROP 1 LAST OFFPAGE TRUE
J 0
(-6050 11850);
DISPLAY 0.872340 (-6050 11850);
PAINT GREEN (-6050 11850);
DISPLAY INVISIBLE (-6050 11850);
FORCEPROP 1 LAST COMMENT_BODY TRUE
J 0
(-6250 11875);
DISPLAY 0.872340 (-6250 11875);
PAINT GREEN (-6250 11875);
DISPLAY INVISIBLE (-6250 11875);
FORCEPROP 2 LAST PATH I128
J 0
(-6575 12025);
DISPLAY 0.680851 (-6575 12025);
DISPLAY INVISIBLE (-6575 12025);
FORCEADD OFFPAGE..1
(-6375 12125);
FORCEPROP 2 LAST $XR0 28 
J 0
(-6596 12125);
DISPLAY 0.638298 (-6596 12125);
PAINT MONO (-6596 12125);
FORCEPROP 2 LAST CDS_LIB standard
J 0
(-6375 12125);
DISPLAY INVISIBLE (-6375 12125);
FORCEPROP 1 LAST OFFPAGE TRUE
J 0
(-6050 12000);
DISPLAY 0.872340 (-6050 12000);
PAINT GREEN (-6050 12000);
DISPLAY INVISIBLE (-6050 12000);
FORCEPROP 1 LAST COMMENT_BODY TRUE
J 0
(-6250 12025);
DISPLAY 0.872340 (-6250 12025);
PAINT GREEN (-6250 12025);
DISPLAY INVISIBLE (-6250 12025);
FORCEPROP 2 LAST PATH I129
J 0
(-6575 12175);
DISPLAY 0.680851 (-6575 12175);
DISPLAY INVISIBLE (-6575 12175);
FORCEADD OFFPAGE..2
R 2
(-8750 8225);
FORCEPROP 2 LAST $XR1 81 
J 0
(-9064 8225);
DISPLAY 0.638298 (-9064 8225);
PAINT MONO (-9064 8225);
FORCEPROP 2 LAST $XR0 28 
J 0
(-8974 8225);
DISPLAY 0.638298 (-8974 8225);
PAINT MONO (-8974 8225);
FORCEPROP 2 LAST CDS_LIB standard
J 0
(-8750 8225);
DISPLAY INVISIBLE (-8750 8225);
FORCEPROP 1 LAST OFFPAGE TRUE
J 2
(-9075 8100);
DISPLAY 0.872340 (-9075 8100);
PAINT GREEN (-9075 8100);
DISPLAY INVISIBLE (-9075 8100);
FORCEPROP 1 LAST COMMENT_BODY TRUE
J 2
(-8705 8130);
DISPLAY 0.872340 (-8705 8130);
PAINT GREEN (-8705 8130);
DISPLAY INVISIBLE (-8705 8130);
FORCEPROP 2 LAST PATH I13
J 0
(-8950 8275);
DISPLAY 0.680851 (-8950 8275);
DISPLAY INVISIBLE (-8950 8275);
FORCEADD OFFPAGE..1
(-6375 12175);
FORCEPROP 2 LAST $XR0 28 
J 0
(-6596 12175);
DISPLAY 0.638298 (-6596 12175);
PAINT MONO (-6596 12175);
FORCEPROP 2 LAST CDS_LIB standard
J 0
(-6375 12175);
DISPLAY INVISIBLE (-6375 12175);
FORCEPROP 1 LAST OFFPAGE TRUE
J 0
(-6050 12050);
DISPLAY 0.872340 (-6050 12050);
PAINT GREEN (-6050 12050);
DISPLAY INVISIBLE (-6050 12050);
FORCEPROP 1 LAST COMMENT_BODY TRUE
J 0
(-6250 12075);
DISPLAY 0.872340 (-6250 12075);
PAINT GREEN (-6250 12075);
DISPLAY INVISIBLE (-6250 12075);
FORCEPROP 2 LAST PATH I130
J 0
(-6575 12225);
DISPLAY 0.680851 (-6575 12225);
DISPLAY INVISIBLE (-6575 12225);
FORCEADD OFFPAGE..1
(-6375 12475);
FORCEPROP 2 LAST $XR1 81 
J 0
(-6686 12475);
DISPLAY 0.638298 (-6686 12475);
PAINT MONO (-6686 12475);
FORCEPROP 2 LAST $XR0 28 
J 0
(-6596 12475);
DISPLAY 0.638298 (-6596 12475);
PAINT MONO (-6596 12475);
FORCEPROP 2 LAST CDS_LIB standard
J 0
(-6375 12475);
DISPLAY INVISIBLE (-6375 12475);
FORCEPROP 1 LAST OFFPAGE TRUE
J 0
(-6050 12350);
DISPLAY 0.872340 (-6050 12350);
PAINT GREEN (-6050 12350);
DISPLAY INVISIBLE (-6050 12350);
FORCEPROP 1 LAST COMMENT_BODY TRUE
J 0
(-6250 12375);
DISPLAY 0.872340 (-6250 12375);
PAINT GREEN (-6250 12375);
DISPLAY INVISIBLE (-6250 12375);
FORCEPROP 2 LAST PATH I131
J 0
(-6575 12525);
DISPLAY 0.680851 (-6575 12525);
DISPLAY INVISIBLE (-6575 12525);
FORCEADD OFFPAGE..1
(-7225 12425);
FORCEPROP 2 LAST $XR2 255 
J 0
(-7686 12425);
DISPLAY 0.638298 (-7686 12425);
PAINT MONO (-7686 12425);
FORCEPROP 2 LAST $XR1 81 
J 0
(-7566 12425);
DISPLAY 0.638298 (-7566 12425);
PAINT MONO (-7566 12425);
FORCEPROP 2 LAST $XR0 28 
J 0
(-7476 12425);
DISPLAY 0.638298 (-7476 12425);
PAINT MONO (-7476 12425);
FORCEPROP 2 LAST CDS_LIB standard
J 0
(-7225 12425);
DISPLAY INVISIBLE (-7225 12425);
FORCEPROP 1 LAST OFFPAGE TRUE
J 0
(-6900 12300);
DISPLAY 0.872340 (-6900 12300);
PAINT GREEN (-6900 12300);
DISPLAY INVISIBLE (-6900 12300);
FORCEPROP 1 LAST COMMENT_BODY TRUE
J 0
(-7100 12325);
DISPLAY 0.872340 (-7100 12325);
PAINT GREEN (-7100 12325);
DISPLAY INVISIBLE (-7100 12325);
FORCEPROP 2 LAST PATH I132
J 0
(-7425 12475);
DISPLAY 0.680851 (-7425 12475);
DISPLAY INVISIBLE (-7425 12475);
FORCEADD OFFPAGE..1
(-6375 12325);
FORCEPROP 2 LAST $XR1 81 
J 0
(-6686 12325);
DISPLAY 0.638298 (-6686 12325);
PAINT MONO (-6686 12325);
FORCEPROP 2 LAST $XR0 28 
J 0
(-6596 12325);
DISPLAY 0.638298 (-6596 12325);
PAINT MONO (-6596 12325);
FORCEPROP 2 LAST CDS_LIB standard
J 0
(-6375 12325);
DISPLAY INVISIBLE (-6375 12325);
FORCEPROP 1 LAST OFFPAGE TRUE
J 0
(-6050 12200);
DISPLAY 0.872340 (-6050 12200);
PAINT GREEN (-6050 12200);
DISPLAY INVISIBLE (-6050 12200);
FORCEPROP 1 LAST COMMENT_BODY TRUE
J 0
(-6250 12225);
DISPLAY 0.872340 (-6250 12225);
PAINT GREEN (-6250 12225);
DISPLAY INVISIBLE (-6250 12225);
FORCEPROP 2 LAST PATH I133
J 0
(-6575 12375);
DISPLAY 0.680851 (-6575 12375);
DISPLAY INVISIBLE (-6575 12375);
FORCEADD OFFPAGE..1
(-6375 12525);
FORCEPROP 2 LAST $XR1 81 
J 0
(-6686 12525);
DISPLAY 0.638298 (-6686 12525);
PAINT MONO (-6686 12525);
FORCEPROP 2 LAST $XR0 28 
J 0
(-6596 12525);
DISPLAY 0.638298 (-6596 12525);
PAINT MONO (-6596 12525);
FORCEPROP 2 LAST CDS_LIB standard
J 0
(-6375 12525);
DISPLAY INVISIBLE (-6375 12525);
FORCEPROP 1 LAST OFFPAGE TRUE
J 0
(-6050 12400);
DISPLAY 0.872340 (-6050 12400);
PAINT GREEN (-6050 12400);
DISPLAY INVISIBLE (-6050 12400);
FORCEPROP 1 LAST COMMENT_BODY TRUE
J 0
(-6250 12425);
DISPLAY 0.872340 (-6250 12425);
PAINT GREEN (-6250 12425);
DISPLAY INVISIBLE (-6250 12425);
FORCEPROP 2 LAST PATH I134
J 0
(-6575 12575);
DISPLAY 0.680851 (-6575 12575);
DISPLAY INVISIBLE (-6575 12575);
FORCEADD Q_RES..1
(-6500 12625);
FORCEPROP 1 LAST LOCATION R249
J 0
(-6375 12625);
DISPLAY 0.489362 (-6375 12625);
PAINT SKYBLUE (-6375 12625);
FORCEPROP 0 LAST $SEC 1
J 2
(-6375 12675);
DISPLAY 0.680851 (-6375 12675);
PAINT MONO (-6375 12675);
DISPLAY INVISIBLE (-6375 12675);
FORCEPROP 0 LAST CDS_SEC 1
J 2
(-6375 12675);
DISPLAY 1.021277 (-6375 12675);
DISPLAY INVISIBLE (-6375 12675);
FORCEPROP 1 LASTPIN (-6600 12625) $PN 1
J 0
(-6588 12637);
DISPLAY 0.489362 (-6588 12637);
PAINT MONO (-6588 12637);
FORCEPROP 1 LASTPIN (-6400 12625) $PN 2
J 0
(-6438 12637);
DISPLAY 0.489362 (-6438 12637);
PAINT MONO (-6438 12637);
FORCEPROP 1 LAST VALUE 33
J 2
(-6625 12625);
DISPLAY 0.489362 (-6625 12625);
PAINT SKYBLUE (-6625 12625);
FORCEPROP 2 LAST CDS_LIB pure_quanta
J 2
(-6500 12625);
DISPLAY INVISIBLE (-6500 12625);
FORCEPROP 2 LAST BOM_COST MEM
J 2
(-6475 12775);
DISPLAY 0.744681 (-6475 12775);
PAINT WHITE (-6475 12775);
DISPLAY INVISIBLE (-6475 12775);
FORCEPROP 1 LAST WATTAGE 1/16W
J 2
(-6575 12550);
DISPLAY 0.489362 (-6575 12550);
PAINT SKYBLUE (-6575 12550);
DISPLAY INVISIBLE (-6575 12550);
FORCEPROP 1 LAST MATERIAL CHIP
J 2
(-6325 12600);
DISPLAY 0.489362 (-6325 12600);
PAINT SKYBLUE (-6325 12600);
DISPLAY INVISIBLE (-6325 12600);
FORCEPROP 1 LAST TOLERANCE 5%
J 0
(-6625 12600);
DISPLAY 0.489362 (-6625 12600);
PAINT SKYBLUE (-6625 12600);
DISPLAY INVISIBLE (-6625 12600);
FORCEPROP 1 LAST PACK_TYPE 0402LF
J 2
(-6325 12550);
DISPLAY 0.489362 (-6325 12550);
PAINT SKYBLUE (-6325 12550);
DISPLAY INVISIBLE (-6325 12550);
FORCEPROP 1 LAST PATH I135
J 0
(-6550 12775);
DISPLAY 0.978723 (-6550 12775);
PAINT WHITE (-6550 12775);
DISPLAY INVISIBLE (-6550 12775);
FORCEPROP 1 LAST PART_NUMBER CS03302JB10
J 2
(-6400 12675);
DISPLAY 0.489362 (-6400 12675);
PAINT SKYBLUE (-6400 12675);
DISPLAY INVISIBLE (-6400 12675);
FORCEADD Q_RES..1
(-6500 12675);
FORCEPROP 1 LAST LOCATION R248
J 0
(-6375 12675);
DISPLAY 0.489362 (-6375 12675);
PAINT SKYBLUE (-6375 12675);
FORCEPROP 0 LAST $SEC 1
J 2
(-6375 12725);
DISPLAY 0.680851 (-6375 12725);
PAINT MONO (-6375 12725);
DISPLAY INVISIBLE (-6375 12725);
FORCEPROP 0 LAST CDS_SEC 1
J 2
(-6375 12725);
DISPLAY 1.021277 (-6375 12725);
DISPLAY INVISIBLE (-6375 12725);
FORCEPROP 1 LASTPIN (-6600 12675) $PN 1
J 0
(-6588 12687);
DISPLAY 0.489362 (-6588 12687);
PAINT MONO (-6588 12687);
FORCEPROP 1 LASTPIN (-6400 12675) $PN 2
J 0
(-6438 12687);
DISPLAY 0.489362 (-6438 12687);
PAINT MONO (-6438 12687);
FORCEPROP 1 LAST VALUE 33
J 2
(-6625 12675);
DISPLAY 0.489362 (-6625 12675);
PAINT SKYBLUE (-6625 12675);
FORCEPROP 2 LAST CDS_LIB pure_quanta
J 2
(-6500 12675);
DISPLAY INVISIBLE (-6500 12675);
FORCEPROP 2 LAST BOM_COST MEM
J 2
(-6475 12825);
DISPLAY 0.744681 (-6475 12825);
PAINT WHITE (-6475 12825);
DISPLAY INVISIBLE (-6475 12825);
FORCEPROP 1 LAST WATTAGE 1/16W
J 2
(-6575 12600);
DISPLAY 0.489362 (-6575 12600);
PAINT SKYBLUE (-6575 12600);
DISPLAY INVISIBLE (-6575 12600);
FORCEPROP 1 LAST MATERIAL CHIP
J 2
(-6325 12650);
DISPLAY 0.489362 (-6325 12650);
PAINT SKYBLUE (-6325 12650);
DISPLAY INVISIBLE (-6325 12650);
FORCEPROP 1 LAST TOLERANCE 5%
J 0
(-6625 12650);
DISPLAY 0.489362 (-6625 12650);
PAINT SKYBLUE (-6625 12650);
DISPLAY INVISIBLE (-6625 12650);
FORCEPROP 1 LAST PACK_TYPE 0402LF
J 2
(-6325 12600);
DISPLAY 0.489362 (-6325 12600);
PAINT SKYBLUE (-6325 12600);
DISPLAY INVISIBLE (-6325 12600);
FORCEPROP 1 LAST PATH I136
J 0
(-6550 12825);
DISPLAY 0.978723 (-6550 12825);
PAINT WHITE (-6550 12825);
DISPLAY INVISIBLE (-6550 12825);
FORCEPROP 1 LAST PART_NUMBER CS03302JB10
J 2
(-6400 12725);
DISPLAY 0.489362 (-6400 12725);
PAINT SKYBLUE (-6400 12725);
DISPLAY INVISIBLE (-6400 12725);
FORCEADD UNIVERSAL_GND..1
(-3900 7725);
FORCEPROP 3 LASTPIN (-3900 7775) SIG_NAME GND\g
J 0
(-3890 7785);
DISPLAY 0.659574 (-3890 7785);
PAINT MONO (-3890 7785);
DISPLAY INVISIBLE (-3890 7785);
FORCEPROP 2 LAST CDS_LIB pure_quanta_power
J 0
(-3900 7725);
DISPLAY INVISIBLE (-3900 7725);
FORCEPROP 1 LAST HDL_POWER GND
J 1
(-3875 7650);
DISPLAY 0.872340 (-3875 7650);
PAINT GREEN (-3875 7650);
DISPLAY INVISIBLE (-3875 7650);
FORCEPROP 1 LAST PATH I137
J 0
(-3825 7725);
DISPLAY 0.872340 (-3825 7725);
PAINT AQUA (-3825 7725);
DISPLAY INVISIBLE (-3825 7725);
FORCEADD Q_CRYSTAL..1
(-3350 8750);
FORCEPROP 1 LAST LOCATION Y3
J 0
(-3425 8950);
DISPLAY 0.489362 (-3425 8950);
PAINT SKYBLUE (-3425 8950);
FORCEPROP 0 LAST $SEC 1
J 0
(-3425 9100);
DISPLAY 0.680851 (-3425 9100);
PAINT MONO (-3425 9100);
DISPLAY INVISIBLE (-3425 9100);
FORCEPROP 0 LAST CDS_SEC 1
J 0
(-3425 9100);
DISPLAY 1.021277 (-3425 9100);
DISPLAY INVISIBLE (-3425 9100);
FORCEPROP 0 LASTPIN (-3450 8750) $PN 1
J 2
(-3460 8760);
DISPLAY 0.489362 (-3460 8760);
PAINT MONO (-3460 8760);
FORCEPROP 0 LASTPIN (-3250 8750) $PN 2
J 0
(-3240 8760);
DISPLAY 0.489362 (-3240 8760);
PAINT MONO (-3240 8760);
FORCEPROP 1 LAST MATERIAL IC
J 0
(-3425 8850);
DISPLAY 0.489362 (-3425 8850);
PAINT SKYBLUE (-3425 8850);
FORCEPROP 2 LAST VALUE 32.768KHZ
J 0
(-3425 9045);
DISPLAY 0.489362 (-3425 9045);
PAINT SKYBLUE (-3425 9045);
FORCEPROP 2 LAST PACK_TYPE SMLF
J 0
(-3425 8995);
DISPLAY 0.489362 (-3425 8995);
PAINT SKYBLUE (-3425 8995);
FORCEPROP 2 LAST CDS_LIB pure_quanta
J 0
(-3350 8750);
DISPLAY INVISIBLE (-3350 8750);
FORCEPROP 1 LAST NEEDS_NO_SIZE TRUE
J 0
(-3350 8750);
DISPLAY 0.468085 (-3350 8750);
PAINT GREEN (-3350 8750);
DISPLAY INVISIBLE (-3350 8750);
FORCEPROP 1 LAST PATH I140
J 0
(-3300 8835);
DISPLAY 0.723404 (-3300 8835);
PAINT GREEN (-3300 8835);
DISPLAY INVISIBLE (-3300 8835);
FORCEPROP 1 LAST PART_NUMBER BG632768012
J 0
(-3425 8905);
DISPLAY 0.489362 (-3425 8905);
PAINT SKYBLUE (-3425 8905);
DISPLAY INVISIBLE (-3425 8905);
FORCEADD UNIVERSAL_GND..1
(-2800 7725);
FORCEPROP 3 LASTPIN (-2800 7775) SIG_NAME GND\g
J 0
(-2790 7785);
DISPLAY 0.659574 (-2790 7785);
PAINT MONO (-2790 7785);
DISPLAY INVISIBLE (-2790 7785);
FORCEPROP 2 LAST CDS_LIB pure_quanta_power
J 0
(-2800 7725);
DISPLAY INVISIBLE (-2800 7725);
FORCEPROP 1 LAST HDL_POWER GND
J 1
(-2775 7650);
DISPLAY 0.872340 (-2775 7650);
PAINT GREEN (-2775 7650);
DISPLAY INVISIBLE (-2775 7650);
FORCEPROP 1 LAST PATH I141
J 0
(-2725 7725);
DISPLAY 0.872340 (-2725 7725);
PAINT AQUA (-2725 7725);
DISPLAY INVISIBLE (-2725 7725);
FORCEADD OFFPAGE..2
(-2275 9125);
FORCEPROP 2 LAST $XR0 28 
J 0
(-2086 9125);
DISPLAY 0.638298 (-2086 9125);
PAINT MONO (-2086 9125);
FORCEPROP 2 LAST CDS_LIB standard
J 0
(-2275 9125);
DISPLAY INVISIBLE (-2275 9125);
FORCEPROP 1 LAST OFFPAGE TRUE
J 0
(-1950 9000);
DISPLAY 0.872340 (-1950 9000);
PAINT GREEN (-1950 9000);
DISPLAY INVISIBLE (-1950 9000);
FORCEPROP 1 LAST COMMENT_BODY TRUE
J 0
(-2320 9030);
DISPLAY 0.872340 (-2320 9030);
PAINT GREEN (-2320 9030);
DISPLAY INVISIBLE (-2320 9030);
FORCEPROP 2 LAST PATH I143
J 0
(-2075 9175);
DISPLAY 0.680851 (-2075 9175);
DISPLAY INVISIBLE (-2075 9175);
FORCEADD OFFPAGE..2
(-2275 9175);
FORCEPROP 2 LAST $XR0 28 
J 0
(-2086 9175);
DISPLAY 0.638298 (-2086 9175);
PAINT MONO (-2086 9175);
FORCEPROP 2 LAST CDS_LIB standard
J 2
(-2275 9175);
DISPLAY INVISIBLE (-2275 9175);
FORCEPROP 1 LAST OFFPAGE TRUE
J 0
(-1950 9050);
DISPLAY 0.872340 (-1950 9050);
PAINT GREEN (-1950 9050);
DISPLAY INVISIBLE (-1950 9050);
FORCEPROP 1 LAST COMMENT_BODY TRUE
J 0
(-2320 9080);
DISPLAY 0.872340 (-2320 9080);
PAINT GREEN (-2320 9080);
DISPLAY INVISIBLE (-2320 9080);
FORCEPROP 2 LAST PATH I144
J 0
(-2075 9225);
DISPLAY 0.680851 (-2075 9225);
DISPLAY INVISIBLE (-2075 9225);
FORCEADD OFFPAGE..1
R 2
(-2125 9825);
FORCEPROP 2 LAST $XR0 84 
J 0
(-1939 9825);
DISPLAY 0.638298 (-1939 9825);
PAINT MONO (-1939 9825);
FORCEPROP 2 LAST CDS_LIB standard
J 0
(-2125 9825);
DISPLAY INVISIBLE (-2125 9825);
FORCEPROP 1 LAST OFFPAGE TRUE
J 2
(-2450 9700);
DISPLAY 0.872340 (-2450 9700);
PAINT GREEN (-2450 9700);
DISPLAY INVISIBLE (-2450 9700);
FORCEPROP 1 LAST COMMENT_BODY TRUE
J 2
(-2250 9725);
DISPLAY 0.872340 (-2250 9725);
PAINT GREEN (-2250 9725);
DISPLAY INVISIBLE (-2250 9725);
FORCEPROP 2 LAST PATH I145
J 0
(-1950 9900);
DISPLAY 0.680851 (-1950 9900);
DISPLAY INVISIBLE (-1950 9900);
FORCEADD OFFPAGE..1
R 2
(-2125 9775);
FORCEPROP 2 LAST $XR0 84 
J 0
(-1939 9775);
DISPLAY 0.638298 (-1939 9775);
PAINT MONO (-1939 9775);
FORCEPROP 2 LAST CDS_LIB standard
J 0
(-2125 9775);
DISPLAY INVISIBLE (-2125 9775);
FORCEPROP 1 LAST OFFPAGE TRUE
J 2
(-2450 9650);
DISPLAY 0.872340 (-2450 9650);
PAINT GREEN (-2450 9650);
DISPLAY INVISIBLE (-2450 9650);
FORCEPROP 1 LAST COMMENT_BODY TRUE
J 2
(-2250 9675);
DISPLAY 0.872340 (-2250 9675);
PAINT GREEN (-2250 9675);
DISPLAY INVISIBLE (-2250 9675);
FORCEPROP 2 LAST PATH I146
J 0
(-1950 9850);
DISPLAY 0.680851 (-1950 9850);
DISPLAY INVISIBLE (-1950 9850);
FORCEADD OFFPAGE..1
R 2
(-2125 9875);
FORCEPROP 2 LAST $XR0 84 
J 0
(-1939 9875);
DISPLAY 0.638298 (-1939 9875);
PAINT MONO (-1939 9875);
FORCEPROP 2 LAST CDS_LIB standard
J 0
(-2125 9875);
DISPLAY INVISIBLE (-2125 9875);
FORCEPROP 1 LAST OFFPAGE TRUE
J 2
(-2450 9750);
DISPLAY 0.872340 (-2450 9750);
PAINT GREEN (-2450 9750);
DISPLAY INVISIBLE (-2450 9750);
FORCEPROP 1 LAST COMMENT_BODY TRUE
J 2
(-2250 9775);
DISPLAY 0.872340 (-2250 9775);
PAINT GREEN (-2250 9775);
DISPLAY INVISIBLE (-2250 9775);
FORCEPROP 2 LAST PATH I147
J 0
(-1950 9950);
DISPLAY 0.680851 (-1950 9950);
DISPLAY INVISIBLE (-1950 9950);
FORCEADD OFFPAGE..3
(-2125 10025);
FORCEPROP 2 LAST $XR0 161 
J 0
(-1911 10025);
DISPLAY 0.638298 (-1911 10025);
PAINT MONO (-1911 10025);
FORCEPROP 2 LAST CDS_LIB standard
J 0
(-2125 10025);
DISPLAY INVISIBLE (-2125 10025);
FORCEPROP 1 LAST OFFPAGE TRUE
J 0
(-1800 9900);
DISPLAY 0.872340 (-1800 9900);
PAINT GREEN (-1800 9900);
DISPLAY INVISIBLE (-1800 9900);
FORCEPROP 1 LAST COMMENT_BODY TRUE
J 0
(-2175 9925);
DISPLAY 0.872340 (-2175 9925);
PAINT PEACH (-2175 9925);
DISPLAY INVISIBLE (-2175 9925);
FORCEPROP 2 LAST PATH I148
J 0
(-1900 10075);
DISPLAY 0.680851 (-1900 10075);
DISPLAY INVISIBLE (-1900 10075);
FORCEADD OFFPAGE..2
(-600 11025);
FORCEPROP 2 LAST $XR0 122 
J 0
(-411 11025);
DISPLAY 0.638298 (-411 11025);
PAINT MONO (-411 11025);
FORCEPROP 2 LAST CDS_LIB standard
J 0
(-600 11025);
DISPLAY INVISIBLE (-600 11025);
FORCEPROP 1 LAST OFFPAGE TRUE
J 0
(-275 10900);
DISPLAY 0.872340 (-275 10900);
PAINT GREEN (-275 10900);
DISPLAY INVISIBLE (-275 10900);
FORCEPROP 1 LAST COMMENT_BODY TRUE
J 0
(-645 10930);
DISPLAY 0.872340 (-645 10930);
PAINT GREEN (-645 10930);
DISPLAY INVISIBLE (-645 10930);
FORCEPROP 2 LAST PATH I150
J 0
(-400 11075);
DISPLAY 0.680851 (-400 11075);
DISPLAY INVISIBLE (-400 11075);
FORCEADD Q_RES..1
(-2000 11025);
FORCEPROP 1 LAST LOCATION R2660
J 0
(-2150 11025);
DISPLAY 0.510638 (-2150 11025);
FORCEPROP 0 LAST $SEC 1
J 0
(-1575 11050);
DISPLAY 0.680851 (-1575 11050);
PAINT MONO (-1575 11050);
DISPLAY INVISIBLE (-1575 11050);
FORCEPROP 0 LAST CDS_SEC 1
J 0
(-1575 11050);
DISPLAY 0.680851 (-1575 11050);
DISPLAY INVISIBLE (-1575 11050);
FORCEPROP 1 LASTPIN (-2100 11025) $PN 1
J 0
(-2088 11037);
DISPLAY 0.787234 (-2088 11037);
PAINT MONO (-2088 11037);
FORCEPROP 1 LASTPIN (-1900 11025) $PN 2
J 0
(-1938 11037);
DISPLAY 0.787234 (-1938 11037);
PAINT MONO (-1938 11037);
FORCEPROP 1 LAST TOLERANCE 5%
J 0
(-1825 11025);
DISPLAY 0.510638 (-1825 11025);
FORCEPROP 1 LAST VALUE 0
J 2
(-1875 11025);
DISPLAY 0.510638 (-1875 11025);
FORCEPROP 1 LAST WATTAGE 1/16W
J 2
(-1575 11025);
DISPLAY 0.510638 (-1575 11025);
FORCEPROP 1 LAST PACK_TYPE 0402LF
J 0
(-2325 11025);
DISPLAY 0.510638 (-2325 11025);
FORCEPROP 1 LAST MATERIAL CHIP
J 0
(-2275 11075);
DISPLAY 0.638298 (-2275 11075);
DISPLAY INVISIBLE (-2275 11075);
FORCEPROP 2 LAST CDS_LIB pure_quanta
J 0
(-2000 11025);
DISPLAY INVISIBLE (-2000 11025);
FORCEPROP 1 LAST PATH I151
J 0
(-2050 11175);
DISPLAY 0.978723 (-2050 11175);
PAINT WHITE (-2050 11175);
DISPLAY INVISIBLE (-2050 11175);
FORCEPROP 1 LAST PART_NUMBER CS00002JB13
J 0
(-2150 11075);
DISPLAY 0.638298 (-2150 11075);
DISPLAY INVISIBLE (-2150 11075);
FORCEADD Q_RES..1
(-2000 11075);
FORCEPROP 1 LAST LOCATION R2659
J 0
(-2150 11075);
DISPLAY 0.510638 (-2150 11075);
FORCEPROP 0 LAST $SEC 1
J 0
(-1575 11100);
DISPLAY 0.680851 (-1575 11100);
PAINT MONO (-1575 11100);
DISPLAY INVISIBLE (-1575 11100);
FORCEPROP 0 LAST CDS_SEC 1
J 0
(-1575 11100);
DISPLAY 0.680851 (-1575 11100);
DISPLAY INVISIBLE (-1575 11100);
FORCEPROP 1 LASTPIN (-2100 11075) $PN 1
J 0
(-2088 11087);
DISPLAY 0.787234 (-2088 11087);
PAINT MONO (-2088 11087);
FORCEPROP 1 LASTPIN (-1900 11075) $PN 2
J 0
(-1938 11087);
DISPLAY 0.787234 (-1938 11087);
PAINT MONO (-1938 11087);
FORCEPROP 1 LAST WATTAGE 1/16W
J 2
(-1575 11075);
DISPLAY 0.510638 (-1575 11075);
FORCEPROP 1 LAST PACK_TYPE 0402LF
J 0
(-2325 11075);
DISPLAY 0.510638 (-2325 11075);
FORCEPROP 1 LAST VALUE 0
J 2
(-1875 11075);
DISPLAY 0.510638 (-1875 11075);
FORCEPROP 1 LAST TOLERANCE 5%
J 0
(-1825 11075);
DISPLAY 0.510638 (-1825 11075);
FORCEPROP 2 LAST CDS_LIB pure_quanta
J 0
(-2000 11075);
DISPLAY INVISIBLE (-2000 11075);
FORCEPROP 1 LAST MATERIAL CHIP
J 0
(-2275 11125);
DISPLAY 0.638298 (-2275 11125);
DISPLAY INVISIBLE (-2275 11125);
FORCEPROP 1 LAST PATH I152
J 0
(-2050 11225);
DISPLAY 0.978723 (-2050 11225);
PAINT WHITE (-2050 11225);
DISPLAY INVISIBLE (-2050 11225);
FORCEPROP 1 LAST PART_NUMBER CS00002JB13
J 0
(-2150 11125);
DISPLAY 0.638298 (-2150 11125);
DISPLAY INVISIBLE (-2150 11125);
FORCEADD Q_RES..1
(-2000 11375);
FORCEPROP 1 LAST LOCATION R9273
J 0
(-2150 11375);
DISPLAY 0.510638 (-2150 11375);
FORCEPROP 0 LAST $SEC 1
J 0
(-1575 11400);
DISPLAY 0.680851 (-1575 11400);
PAINT MONO (-1575 11400);
DISPLAY INVISIBLE (-1575 11400);
FORCEPROP 0 LAST CDS_SEC 1
J 0
(-1575 11400);
DISPLAY 0.680851 (-1575 11400);
DISPLAY INVISIBLE (-1575 11400);
FORCEPROP 1 LASTPIN (-2100 11375) $PN 1
J 0
(-2088 11387);
DISPLAY 0.787234 (-2088 11387);
PAINT MONO (-2088 11387);
FORCEPROP 1 LASTPIN (-1900 11375) $PN 2
J 0
(-1938 11387);
DISPLAY 0.787234 (-1938 11387);
PAINT MONO (-1938 11387);
FORCEPROP 1 LAST PACK_TYPE 0402LF
J 0
(-2325 11375);
DISPLAY 0.510638 (-2325 11375);
FORCEPROP 1 LAST TOLERANCE 5%
J 0
(-1825 11375);
DISPLAY 0.510638 (-1825 11375);
FORCEPROP 1 LAST VALUE 0
J 2
(-1875 11375);
DISPLAY 0.510638 (-1875 11375);
FORCEPROP 1 LAST WATTAGE 1/16W
J 2
(-1575 11375);
DISPLAY 0.510638 (-1575 11375);
FORCEPROP 2 LAST CDS_LIB pure_quanta
J 0
(-2000 11375);
DISPLAY INVISIBLE (-2000 11375);
FORCEPROP 1 LAST MATERIAL CHIP
J 0
(-2275 11425);
DISPLAY 0.638298 (-2275 11425);
DISPLAY INVISIBLE (-2275 11425);
FORCEPROP 1 LAST PATH I153
J 0
(-2050 11525);
DISPLAY 0.978723 (-2050 11525);
PAINT WHITE (-2050 11525);
DISPLAY INVISIBLE (-2050 11525);
FORCEPROP 1 LAST PART_NUMBER CS00002JB13
J 0
(-2150 11425);
DISPLAY 0.638298 (-2150 11425);
DISPLAY INVISIBLE (-2150 11425);
FORCEADD Q_RES..1
(-2000 11325);
FORCEPROP 1 LAST LOCATION R9274
J 0
(-2150 11325);
DISPLAY 0.510638 (-2150 11325);
FORCEPROP 0 LAST $SEC 1
J 0
(-1575 11350);
DISPLAY 0.680851 (-1575 11350);
PAINT MONO (-1575 11350);
DISPLAY INVISIBLE (-1575 11350);
FORCEPROP 0 LAST CDS_SEC 1
J 0
(-1575 11350);
DISPLAY 0.680851 (-1575 11350);
DISPLAY INVISIBLE (-1575 11350);
FORCEPROP 1 LASTPIN (-2100 11325) $PN 1
J 0
(-2088 11337);
DISPLAY 0.787234 (-2088 11337);
PAINT MONO (-2088 11337);
FORCEPROP 1 LASTPIN (-1900 11325) $PN 2
J 0
(-1938 11337);
DISPLAY 0.787234 (-1938 11337);
PAINT MONO (-1938 11337);
FORCEPROP 1 LAST PACK_TYPE 0402LF
J 0
(-2325 11325);
DISPLAY 0.510638 (-2325 11325);
FORCEPROP 1 LAST WATTAGE 1/16W
J 2
(-1575 11325);
DISPLAY 0.510638 (-1575 11325);
FORCEPROP 1 LAST VALUE 0
J 2
(-1875 11325);
DISPLAY 0.510638 (-1875 11325);
FORCEPROP 1 LAST TOLERANCE 5%
J 0
(-1825 11325);
DISPLAY 0.510638 (-1825 11325);
FORCEPROP 1 LAST MATERIAL CHIP
J 0
(-2275 11375);
DISPLAY 0.638298 (-2275 11375);
DISPLAY INVISIBLE (-2275 11375);
FORCEPROP 2 LAST CDS_LIB pure_quanta
J 0
(-2000 11325);
DISPLAY INVISIBLE (-2000 11325);
FORCEPROP 1 LAST PATH I154
J 0
(-2050 11475);
DISPLAY 0.978723 (-2050 11475);
PAINT WHITE (-2050 11475);
DISPLAY INVISIBLE (-2050 11475);
FORCEPROP 1 LAST PART_NUMBER CS00002JB13
J 0
(-2150 11375);
DISPLAY 0.638298 (-2150 11375);
DISPLAY INVISIBLE (-2150 11375);
FORCEADD Q_RES..1
(-2000 11475);
FORCEPROP 1 LAST LOCATION R8566
J 0
(-2175 11475);
DISPLAY 0.510638 (-2175 11475);
FORCEPROP 0 LAST $SEC 1
J 0
(-1575 11500);
DISPLAY 0.680851 (-1575 11500);
PAINT MONO (-1575 11500);
DISPLAY INVISIBLE (-1575 11500);
FORCEPROP 0 LAST CDS_SEC 1
J 0
(-1575 11500);
DISPLAY 0.680851 (-1575 11500);
DISPLAY INVISIBLE (-1575 11500);
FORCEPROP 1 LASTPIN (-2100 11475) $PN 1
J 0
(-2088 11487);
DISPLAY 0.787234 (-2088 11487);
PAINT MONO (-2088 11487);
FORCEPROP 1 LASTPIN (-1900 11475) $PN 2
J 0
(-1938 11487);
DISPLAY 0.787234 (-1938 11487);
PAINT MONO (-1938 11487);
FORCEPROP 1 LAST WATTAGE 1/16W
J 2
(-1575 11475);
DISPLAY 0.510638 (-1575 11475);
FORCEPROP 1 LAST VALUE 0
J 2
(-1875 11475);
DISPLAY 0.510638 (-1875 11475);
FORCEPROP 1 LAST TOLERANCE 5%
J 0
(-1825 11475);
DISPLAY 0.510638 (-1825 11475);
FORCEPROP 1 LAST PACK_TYPE 0402LF
J 0
(-2350 11475);
DISPLAY 0.510638 (-2350 11475);
FORCEPROP 1 LAST MATERIAL CHIP
J 0
(-2275 11525);
DISPLAY 0.638298 (-2275 11525);
DISPLAY INVISIBLE (-2275 11525);
FORCEPROP 2 LAST CDS_LIB pure_quanta
J 0
(-2000 11475);
DISPLAY INVISIBLE (-2000 11475);
FORCEPROP 1 LAST PATH I155
J 0
(-2050 11625);
DISPLAY 0.978723 (-2050 11625);
PAINT WHITE (-2050 11625);
DISPLAY INVISIBLE (-2050 11625);
FORCEPROP 1 LAST PART_NUMBER CS00002JB13
J 0
(-2150 11525);
DISPLAY 0.638298 (-2150 11525);
DISPLAY INVISIBLE (-2150 11525);
FORCEADD Q_RES..1
(-2025 11625);
FORCEPROP 1 LAST LOCATION R8564
J 0
(-2175 11625);
DISPLAY 0.510638 (-2175 11625);
FORCEPROP 0 LAST $SEC 1
J 0
(-1600 11650);
DISPLAY 0.680851 (-1600 11650);
PAINT MONO (-1600 11650);
DISPLAY INVISIBLE (-1600 11650);
FORCEPROP 0 LAST CDS_SEC 1
J 0
(-1600 11650);
DISPLAY 0.680851 (-1600 11650);
DISPLAY INVISIBLE (-1600 11650);
FORCEPROP 1 LASTPIN (-2125 11625) $PN 1
J 0
(-2113 11637);
DISPLAY 0.787234 (-2113 11637);
PAINT MONO (-2113 11637);
FORCEPROP 1 LASTPIN (-1925 11625) $PN 2
J 0
(-1963 11637);
DISPLAY 0.787234 (-1963 11637);
PAINT MONO (-1963 11637);
FORCEPROP 1 LAST PACK_TYPE 0402LF
J 0
(-2350 11625);
DISPLAY 0.510638 (-2350 11625);
FORCEPROP 1 LAST TOLERANCE 5%
J 0
(-1850 11625);
DISPLAY 0.510638 (-1850 11625);
FORCEPROP 1 LAST WATTAGE 1/16W
J 2
(-1600 11625);
DISPLAY 0.510638 (-1600 11625);
FORCEPROP 1 LAST VALUE 0
J 2
(-1900 11625);
DISPLAY 0.510638 (-1900 11625);
FORCEPROP 1 LAST MATERIAL CHIP
J 0
(-2300 11675);
DISPLAY 0.638298 (-2300 11675);
DISPLAY INVISIBLE (-2300 11675);
FORCEPROP 2 LAST CDS_LIB pure_quanta
J 0
(-2025 11625);
DISPLAY INVISIBLE (-2025 11625);
FORCEPROP 1 LAST PATH I156
J 0
(-2075 11775);
DISPLAY 0.978723 (-2075 11775);
PAINT WHITE (-2075 11775);
DISPLAY INVISIBLE (-2075 11775);
FORCEPROP 1 LAST PART_NUMBER CS00002JB13
J 0
(-2175 11675);
DISPLAY 0.638298 (-2175 11675);
DISPLAY INVISIBLE (-2175 11675);
FORCEADD Q_RES..1
(-2025 11675);
FORCEPROP 1 LAST LOCATION R8563
J 0
(-2175 11675);
DISPLAY 0.510638 (-2175 11675);
FORCEPROP 0 LAST $SEC 1
J 0
(-2150 11750);
DISPLAY 0.680851 (-2150 11750);
PAINT MONO (-2150 11750);
DISPLAY INVISIBLE (-2150 11750);
FORCEPROP 0 LAST CDS_SEC 1
J 0
(-2150 11750);
DISPLAY 0.680851 (-2150 11750);
DISPLAY INVISIBLE (-2150 11750);
FORCEPROP 1 LASTPIN (-2125 11675) $PN 1
J 0
(-2113 11687);
DISPLAY 0.787234 (-2113 11687);
PAINT MONO (-2113 11687);
FORCEPROP 1 LASTPIN (-1925 11675) $PN 2
J 0
(-1963 11687);
DISPLAY 0.787234 (-1963 11687);
PAINT MONO (-1963 11687);
FORCEPROP 1 LAST PACK_TYPE 0402LF
J 0
(-2350 11675);
DISPLAY 0.510638 (-2350 11675);
FORCEPROP 1 LAST WATTAGE 1/16W
J 2
(-1600 11675);
DISPLAY 0.510638 (-1600 11675);
FORCEPROP 1 LAST MATERIAL CHIP
J 0
(-2300 11725);
DISPLAY 0.510638 (-2300 11725);
FORCEPROP 1 LAST VALUE 0
J 2
(-1900 11675);
DISPLAY 0.510638 (-1900 11675);
FORCEPROP 1 LAST TOLERANCE 5%
J 0
(-1850 11675);
DISPLAY 0.510638 (-1850 11675);
FORCEPROP 2 LAST CDS_LIB pure_quanta
J 0
(-2025 11675);
DISPLAY INVISIBLE (-2025 11675);
FORCEPROP 1 LAST PATH I157
J 0
(-2075 11825);
DISPLAY 0.978723 (-2075 11825);
PAINT WHITE (-2075 11825);
DISPLAY INVISIBLE (-2075 11825);
FORCEPROP 1 LAST PART_NUMBER CS00002JB13
J 0
(-2150 11725);
DISPLAY 0.510638 (-2150 11725);
DISPLAY INVISIBLE (-2150 11725);
FORCEADD Q_RES..1
(-2000 11525);
FORCEPROP 1 LAST LOCATION R8565
J 0
(-2175 11525);
DISPLAY 0.510638 (-2175 11525);
FORCEPROP 0 LAST $SEC 1
J 0
(-1575 11550);
DISPLAY 0.680851 (-1575 11550);
PAINT MONO (-1575 11550);
DISPLAY INVISIBLE (-1575 11550);
FORCEPROP 0 LAST CDS_SEC 1
J 0
(-1575 11550);
DISPLAY 0.680851 (-1575 11550);
DISPLAY INVISIBLE (-1575 11550);
FORCEPROP 1 LASTPIN (-2100 11525) $PN 1
J 0
(-2088 11537);
DISPLAY 0.787234 (-2088 11537);
PAINT MONO (-2088 11537);
FORCEPROP 1 LASTPIN (-1900 11525) $PN 2
J 0
(-1938 11537);
DISPLAY 0.787234 (-1938 11537);
PAINT MONO (-1938 11537);
FORCEPROP 1 LAST VALUE 0
J 2
(-1875 11525);
DISPLAY 0.510638 (-1875 11525);
FORCEPROP 1 LAST WATTAGE 1/16W
J 2
(-1575 11525);
DISPLAY 0.510638 (-1575 11525);
FORCEPROP 1 LAST TOLERANCE 5%
J 0
(-1825 11525);
DISPLAY 0.510638 (-1825 11525);
FORCEPROP 1 LAST PACK_TYPE 0402LF
J 0
(-2350 11525);
DISPLAY 0.510638 (-2350 11525);
FORCEPROP 1 LAST MATERIAL CHIP
J 0
(-2275 11575);
DISPLAY 0.638298 (-2275 11575);
DISPLAY INVISIBLE (-2275 11575);
FORCEPROP 2 LAST CDS_LIB pure_quanta
J 0
(-2000 11525);
DISPLAY INVISIBLE (-2000 11525);
FORCEPROP 1 LAST PATH I158
J 0
(-2050 11675);
DISPLAY 0.978723 (-2050 11675);
PAINT WHITE (-2050 11675);
DISPLAY INVISIBLE (-2050 11675);
FORCEPROP 1 LAST PART_NUMBER CS00002JB13
J 0
(-2150 11575);
DISPLAY 0.638298 (-2150 11575);
DISPLAY INVISIBLE (-2150 11575);
FORCEADD OFFPAGE..2
(-2250 12025);
FORCEPROP 2 LAST $XR1 83 
J 0
(-1971 12025);
DISPLAY 0.638298 (-1971 12025);
PAINT MONO (-1971 12025);
FORCEPROP 2 LAST $XR0 81 
J 0
(-2061 12025);
DISPLAY 0.638298 (-2061 12025);
PAINT MONO (-2061 12025);
FORCEPROP 2 LAST CDS_LIB standard
J 0
(-2250 12025);
DISPLAY INVISIBLE (-2250 12025);
FORCEPROP 1 LAST OFFPAGE TRUE
J 0
(-1925 11900);
DISPLAY 0.872340 (-1925 11900);
PAINT GREEN (-1925 11900);
DISPLAY INVISIBLE (-1925 11900);
FORCEPROP 1 LAST COMMENT_BODY TRUE
J 0
(-2295 11930);
DISPLAY 0.872340 (-2295 11930);
PAINT GREEN (-2295 11930);
DISPLAY INVISIBLE (-2295 11930);
FORCEPROP 2 LAST PATH I159
J 0
(-1950 12075);
DISPLAY 0.680851 (-1950 12075);
DISPLAY INVISIBLE (-1950 12075);
FORCEADD OFFPAGE..2
R 2
(-8750 8675);
FORCEPROP 2 LAST $XR3 85 
J 0
(-9244 8675);
DISPLAY 0.638298 (-9244 8675);
PAINT MONO (-9244 8675);
FORCEPROP 2 LAST $XR2 78 
J 0
(-9154 8675);
DISPLAY 0.638298 (-9154 8675);
PAINT MONO (-9154 8675);
FORCEPROP 2 LAST $XR1 81 
J 0
(-9064 8675);
DISPLAY 0.638298 (-9064 8675);
PAINT MONO (-9064 8675);
FORCEPROP 2 LAST $XR0 28 
J 0
(-8974 8675);
DISPLAY 0.638298 (-8974 8675);
PAINT MONO (-8974 8675);
FORCEPROP 2 LAST CDS_LIB standard
J 0
(-8750 8675);
DISPLAY INVISIBLE (-8750 8675);
FORCEPROP 1 LAST OFFPAGE TRUE
J 2
(-9075 8550);
DISPLAY 0.872340 (-9075 8550);
PAINT GREEN (-9075 8550);
DISPLAY INVISIBLE (-9075 8550);
FORCEPROP 1 LAST COMMENT_BODY TRUE
J 2
(-8705 8580);
DISPLAY 0.872340 (-8705 8580);
PAINT GREEN (-8705 8580);
DISPLAY INVISIBLE (-8705 8580);
FORCEPROP 2 LAST PATH I16
J 0
(-8950 8725);
DISPLAY 0.680851 (-8950 8725);
DISPLAY INVISIBLE (-8950 8725);
FORCEADD Q_RES..1
(-2025 11825);
FORCEPROP 1 LAST LOCATION R4535
J 0
(-2175 11825);
DISPLAY 0.510638 (-2175 11825);
FORCEPROP 0 LAST $SEC 1
J 0
(-2150 11900);
DISPLAY 0.680851 (-2150 11900);
PAINT MONO (-2150 11900);
DISPLAY INVISIBLE (-2150 11900);
FORCEPROP 0 LAST CDS_SEC 1
J 0
(-2150 11900);
DISPLAY 0.680851 (-2150 11900);
DISPLAY INVISIBLE (-2150 11900);
FORCEPROP 1 LASTPIN (-2125 11825) $PN 1
J 0
(-2113 11837);
DISPLAY 0.787234 (-2113 11837);
PAINT MONO (-2113 11837);
FORCEPROP 1 LASTPIN (-1925 11825) $PN 2
J 0
(-1963 11837);
DISPLAY 0.787234 (-1963 11837);
PAINT MONO (-1963 11837);
FORCEPROP 1 LAST PACK_TYPE 0402LF
J 0
(-2350 11825);
DISPLAY 0.510638 (-2350 11825);
FORCEPROP 1 LAST TOLERANCE 5%
J 0
(-1850 11825);
DISPLAY 0.510638 (-1850 11825);
FORCEPROP 1 LAST VALUE 0
J 2
(-1900 11825);
DISPLAY 0.510638 (-1900 11825);
FORCEPROP 1 LAST MATERIAL CHIP
J 0
(-2300 11875);
DISPLAY 0.510638 (-2300 11875);
FORCEPROP 1 LAST WATTAGE 1/16W
J 2
(-1600 11825);
DISPLAY 0.510638 (-1600 11825);
FORCEPROP 2 LAST CDS_LIB pure_quanta
J 0
(-2025 11825);
DISPLAY INVISIBLE (-2025 11825);
FORCEPROP 1 LAST PATH I160
J 0
(-2075 11975);
DISPLAY 0.978723 (-2075 11975);
PAINT WHITE (-2075 11975);
DISPLAY INVISIBLE (-2075 11975);
FORCEPROP 1 LAST PART_NUMBER CS00002JB13
J 0
(-2150 11875);
DISPLAY 0.510638 (-2150 11875);
DISPLAY INVISIBLE (-2150 11875);
FORCEADD Q_RES..1
(-2025 11775);
FORCEPROP 1 LAST LOCATION R4536
J 0
(-2175 11775);
DISPLAY 0.510638 (-2175 11775);
FORCEPROP 0 LAST $SEC 1
J 0
(-1600 11800);
DISPLAY 0.680851 (-1600 11800);
PAINT MONO (-1600 11800);
DISPLAY INVISIBLE (-1600 11800);
FORCEPROP 0 LAST CDS_SEC 1
J 0
(-1600 11800);
DISPLAY 0.680851 (-1600 11800);
DISPLAY INVISIBLE (-1600 11800);
FORCEPROP 1 LASTPIN (-2125 11775) $PN 1
J 0
(-2113 11787);
DISPLAY 0.787234 (-2113 11787);
PAINT MONO (-2113 11787);
FORCEPROP 1 LASTPIN (-1925 11775) $PN 2
J 0
(-1963 11787);
DISPLAY 0.787234 (-1963 11787);
PAINT MONO (-1963 11787);
FORCEPROP 1 LAST TOLERANCE 5%
J 0
(-1850 11775);
DISPLAY 0.510638 (-1850 11775);
FORCEPROP 1 LAST VALUE 0
J 2
(-1900 11775);
DISPLAY 0.510638 (-1900 11775);
FORCEPROP 1 LAST WATTAGE 1/16W
J 2
(-1600 11775);
DISPLAY 0.510638 (-1600 11775);
FORCEPROP 1 LAST PACK_TYPE 0402LF
J 0
(-2350 11775);
DISPLAY 0.510638 (-2350 11775);
FORCEPROP 2 LAST CDS_LIB pure_quanta
J 0
(-2025 11775);
DISPLAY INVISIBLE (-2025 11775);
FORCEPROP 1 LAST MATERIAL CHIP
J 0
(-2300 11825);
DISPLAY 0.638298 (-2300 11825);
DISPLAY INVISIBLE (-2300 11825);
FORCEPROP 1 LAST PATH I161
J 0
(-2075 11925);
DISPLAY 0.978723 (-2075 11925);
PAINT WHITE (-2075 11925);
DISPLAY INVISIBLE (-2075 11925);
FORCEPROP 1 LAST PART_NUMBER CS00002JB13
J 0
(-2175 11825);
DISPLAY 0.638298 (-2175 11825);
DISPLAY INVISIBLE (-2175 11825);
FORCEADD OFFPAGE..2
(-2250 12075);
FORCEPROP 2 LAST $XR1 83 
J 0
(-1971 12075);
DISPLAY 0.638298 (-1971 12075);
PAINT MONO (-1971 12075);
FORCEPROP 2 LAST $XR0 81 
J 0
(-2061 12075);
DISPLAY 0.638298 (-2061 12075);
PAINT MONO (-2061 12075);
FORCEPROP 2 LAST CDS_LIB standard
J 0
(-2250 12075);
DISPLAY INVISIBLE (-2250 12075);
FORCEPROP 1 LAST OFFPAGE TRUE
J 0
(-1925 11950);
DISPLAY 0.872340 (-1925 11950);
PAINT GREEN (-1925 11950);
DISPLAY INVISIBLE (-1925 11950);
FORCEPROP 1 LAST COMMENT_BODY TRUE
J 0
(-2295 11980);
DISPLAY 0.872340 (-2295 11980);
PAINT GREEN (-2295 11980);
DISPLAY INVISIBLE (-2295 11980);
FORCEPROP 2 LAST PATH I162
J 0
(-1950 12125);
DISPLAY 0.680851 (-1950 12125);
DISPLAY INVISIBLE (-1950 12125);
FORCEADD OFFPAGE..2
(-2275 12225);
FORCEPROP 2 LAST $XR1 81 
J 0
(-1996 12225);
DISPLAY 0.638298 (-1996 12225);
PAINT MONO (-1996 12225);
FORCEPROP 2 LAST $XR0 28 
J 0
(-2086 12225);
DISPLAY 0.638298 (-2086 12225);
PAINT MONO (-2086 12225);
FORCEPROP 2 LAST CDS_LIB standard
J 0
(-2275 12225);
DISPLAY INVISIBLE (-2275 12225);
FORCEPROP 1 LAST OFFPAGE TRUE
J 0
(-1950 12100);
DISPLAY 0.872340 (-1950 12100);
PAINT GREEN (-1950 12100);
DISPLAY INVISIBLE (-1950 12100);
FORCEPROP 1 LAST COMMENT_BODY TRUE
J 0
(-2320 12130);
DISPLAY 0.872340 (-2320 12130);
PAINT GREEN (-2320 12130);
DISPLAY INVISIBLE (-2320 12130);
FORCEPROP 2 LAST PATH I163
J 0
(-1975 12275);
DISPLAY 0.680851 (-1975 12275);
DISPLAY INVISIBLE (-1975 12275);
FORCEADD OFFPAGE..1
R 2
(-2275 12325);
FORCEPROP 2 LAST $XR1 81 
J 0
(-1999 12325);
DISPLAY 0.638298 (-1999 12325);
PAINT MONO (-1999 12325);
FORCEPROP 2 LAST $XR0 28 
J 0
(-2089 12325);
DISPLAY 0.638298 (-2089 12325);
PAINT MONO (-2089 12325);
FORCEPROP 2 LAST CDS_LIB standard
J 0
(-2275 12325);
DISPLAY INVISIBLE (-2275 12325);
FORCEPROP 1 LAST OFFPAGE TRUE
J 2
(-2600 12200);
DISPLAY 0.872340 (-2600 12200);
PAINT GREEN (-2600 12200);
DISPLAY INVISIBLE (-2600 12200);
FORCEPROP 1 LAST COMMENT_BODY TRUE
J 2
(-2400 12225);
DISPLAY 0.872340 (-2400 12225);
PAINT GREEN (-2400 12225);
DISPLAY INVISIBLE (-2400 12225);
FORCEPROP 2 LAST PATH I164
J 0
(-1975 12375);
DISPLAY 0.680851 (-1975 12375);
DISPLAY INVISIBLE (-1975 12375);
FORCEADD Q_RES..1
(-2175 12525);
FORCEPROP 1 LAST LOCATION R434
J 0
(-2450 12525);
DISPLAY 0.489362 (-2450 12525);
PAINT SKYBLUE (-2450 12525);
FORCEPROP 0 LAST $SEC 1
J 0
(-2350 12575);
DISPLAY 0.680851 (-2350 12575);
PAINT MONO (-2350 12575);
DISPLAY INVISIBLE (-2350 12575);
FORCEPROP 0 LAST CDS_SEC 1
J 0
(-2350 12575);
DISPLAY 1.021277 (-2350 12575);
DISPLAY INVISIBLE (-2350 12575);
FORCEPROP 1 LASTPIN (-2275 12525) $PN 1
J 0
(-2263 12537);
DISPLAY 0.489362 (-2263 12537);
PAINT MONO (-2263 12537);
FORCEPROP 1 LASTPIN (-2075 12525) $PN 2
J 0
(-2113 12537);
DISPLAY 0.489362 (-2113 12537);
PAINT MONO (-2113 12537);
FORCEPROP 1 LAST VALUE 33
J 2
(-2000 12525);
DISPLAY 0.489362 (-2000 12525);
PAINT SKYBLUE (-2000 12525);
FORCEPROP 1 LAST PACK_TYPE 0402LF
J 0
(-2125 12450);
DISPLAY 0.489362 (-2125 12450);
PAINT SKYBLUE (-2125 12450);
DISPLAY INVISIBLE (-2125 12450);
FORCEPROP 1 LAST TOLERANCE 5%
J 0
(-2200 12450);
DISPLAY 0.489362 (-2200 12450);
PAINT SKYBLUE (-2200 12450);
DISPLAY INVISIBLE (-2200 12450);
FORCEPROP 1 LAST MATERIAL CHIP
J 0
(-1750 12450);
DISPLAY 0.489362 (-1750 12450);
PAINT SKYBLUE (-1750 12450);
DISPLAY INVISIBLE (-1750 12450);
FORCEPROP 1 LAST WATTAGE 1/16W
J 2
(-1775 12450);
DISPLAY 0.489362 (-1775 12450);
PAINT SKYBLUE (-1775 12450);
DISPLAY INVISIBLE (-1775 12450);
FORCEPROP 2 LAST CDS_LIB pure_quanta
J 0
(-2175 12525);
DISPLAY INVISIBLE (-2175 12525);
FORCEPROP 1 LAST PATH I165
J 0
(-2225 12675);
DISPLAY 0.978723 (-2225 12675);
PAINT WHITE (-2225 12675);
DISPLAY INVISIBLE (-2225 12675);
FORCEPROP 1 LAST PART_NUMBER CS03302JB10
J 0
(-2150 12575);
DISPLAY 0.489362 (-2150 12575);
PAINT SKYBLUE (-2150 12575);
DISPLAY INVISIBLE (-2150 12575);
FORCEADD OFFPAGE..2
(-2250 12875);
FORCEPROP 2 LAST $XR1 55 
J 0
(-1971 12875);
DISPLAY 0.638298 (-1971 12875);
PAINT MONO (-1971 12875);
FORCEPROP 2 LAST $XR0 76 
J 0
(-2061 12875);
DISPLAY 0.638298 (-2061 12875);
PAINT MONO (-2061 12875);
FORCEPROP 2 LAST CDS_LIB standard
J 0
(-2250 12875);
DISPLAY INVISIBLE (-2250 12875);
FORCEPROP 1 LAST OFFPAGE TRUE
J 0
(-1925 12750);
DISPLAY 0.872340 (-1925 12750);
PAINT GREEN (-1925 12750);
DISPLAY INVISIBLE (-1925 12750);
FORCEPROP 1 LAST COMMENT_BODY TRUE
J 0
(-2295 12780);
DISPLAY 0.872340 (-2295 12780);
PAINT GREEN (-2295 12780);
DISPLAY INVISIBLE (-2295 12780);
FORCEPROP 2 LAST PATH I166
J 0
(-1950 12925);
DISPLAY 0.680851 (-1950 12925);
DISPLAY INVISIBLE (-1950 12925);
FORCEADD Q_RES..1
(-1975 11225);
FORCEPROP 1 LAST LOCATION R9275
J 0
(-2125 11225);
DISPLAY 0.510638 (-2125 11225);
FORCEPROP 0 LAST $SEC 1
J 0
(-1550 11250);
DISPLAY 0.680851 (-1550 11250);
PAINT MONO (-1550 11250);
DISPLAY INVISIBLE (-1550 11250);
FORCEPROP 0 LAST CDS_SEC 1
J 0
(-1550 11250);
DISPLAY 0.680851 (-1550 11250);
DISPLAY INVISIBLE (-1550 11250);
FORCEPROP 1 LASTPIN (-2075 11225) $PN 1
J 0
(-2063 11237);
DISPLAY 0.787234 (-2063 11237);
PAINT MONO (-2063 11237);
FORCEPROP 1 LASTPIN (-1875 11225) $PN 2
J 0
(-1913 11237);
DISPLAY 0.787234 (-1913 11237);
PAINT MONO (-1913 11237);
FORCEPROP 1 LAST VALUE 0
J 2
(-1850 11225);
DISPLAY 0.510638 (-1850 11225);
FORCEPROP 1 LAST WATTAGE 1/16W
J 2
(-1550 11225);
DISPLAY 0.510638 (-1550 11225);
FORCEPROP 1 LAST TOLERANCE 5%
J 0
(-1800 11225);
DISPLAY 0.510638 (-1800 11225);
FORCEPROP 1 LAST PACK_TYPE 0402LF
J 0
(-2300 11225);
DISPLAY 0.510638 (-2300 11225);
FORCEPROP 1 LAST MATERIAL CHIP
J 0
(-2250 11275);
DISPLAY 0.638298 (-2250 11275);
DISPLAY INVISIBLE (-2250 11275);
FORCEPROP 2 LAST CDS_LIB pure_quanta
J 0
(-1975 11225);
DISPLAY INVISIBLE (-1975 11225);
FORCEPROP 1 LAST PATH I167
J 0
(-2025 11375);
DISPLAY 0.978723 (-2025 11375);
PAINT WHITE (-2025 11375);
DISPLAY INVISIBLE (-2025 11375);
FORCEPROP 1 LAST PART_NUMBER CS00002JB13
J 0
(-2125 11275);
DISPLAY 0.638298 (-2125 11275);
DISPLAY INVISIBLE (-2125 11275);
FORCEADD Q_RES..1
(-1975 11175);
FORCEPROP 1 LAST LOCATION R9276
J 0
(-2125 11175);
DISPLAY 0.510638 (-2125 11175);
FORCEPROP 0 LAST $SEC 1
J 0
(-1550 11200);
DISPLAY 0.680851 (-1550 11200);
PAINT MONO (-1550 11200);
DISPLAY INVISIBLE (-1550 11200);
FORCEPROP 0 LAST CDS_SEC 1
J 0
(-1550 11200);
DISPLAY 0.680851 (-1550 11200);
DISPLAY INVISIBLE (-1550 11200);
FORCEPROP 1 LASTPIN (-2075 11175) $PN 1
J 0
(-2063 11187);
DISPLAY 0.787234 (-2063 11187);
PAINT MONO (-2063 11187);
FORCEPROP 1 LASTPIN (-1875 11175) $PN 2
J 0
(-1913 11187);
DISPLAY 0.787234 (-1913 11187);
PAINT MONO (-1913 11187);
FORCEPROP 1 LAST VALUE 0
J 2
(-1850 11175);
DISPLAY 0.510638 (-1850 11175);
FORCEPROP 1 LAST TOLERANCE 5%
J 0
(-1800 11175);
DISPLAY 0.510638 (-1800 11175);
FORCEPROP 1 LAST WATTAGE 1/16W
J 2
(-1550 11175);
DISPLAY 0.510638 (-1550 11175);
FORCEPROP 1 LAST PACK_TYPE 0402LF
J 0
(-2300 11175);
DISPLAY 0.510638 (-2300 11175);
FORCEPROP 1 LAST MATERIAL CHIP
J 0
(-2250 11225);
DISPLAY 0.638298 (-2250 11225);
DISPLAY INVISIBLE (-2250 11225);
FORCEPROP 2 LAST CDS_LIB pure_quanta
J 0
(-1975 11175);
DISPLAY INVISIBLE (-1975 11175);
FORCEPROP 1 LAST PATH I168
J 0
(-2025 11325);
DISPLAY 0.978723 (-2025 11325);
PAINT WHITE (-2025 11325);
DISPLAY INVISIBLE (-2025 11325);
FORCEPROP 1 LAST PART_NUMBER CS00002JB13
J 0
(-2125 11225);
DISPLAY 0.638298 (-2125 11225);
DISPLAY INVISIBLE (-2125 11225);
FORCEADD OFFPAGE..3
(-1850 12775);
FORCEPROP 2 LAST $XR2 85 
J 0
(-1456 12775);
DISPLAY 0.638298 (-1456 12775);
PAINT MONO (-1456 12775);
FORCEPROP 2 LAST $XR1 81 
J 0
(-1546 12775);
DISPLAY 0.638298 (-1546 12775);
PAINT MONO (-1546 12775);
FORCEPROP 2 LAST $XR0 28 
J 0
(-1636 12775);
DISPLAY 0.638298 (-1636 12775);
PAINT MONO (-1636 12775);
FORCEPROP 2 LAST CDS_LIB standard
J 2
(-1850 12775);
DISPLAY INVISIBLE (-1850 12775);
FORCEPROP 1 LAST OFFPAGE TRUE
J 0
(-1525 12650);
DISPLAY 0.872340 (-1525 12650);
PAINT GREEN (-1525 12650);
DISPLAY INVISIBLE (-1525 12650);
FORCEPROP 1 LAST COMMENT_BODY TRUE
J 0
(-1900 12675);
DISPLAY 0.872340 (-1900 12675);
PAINT PEACH (-1900 12675);
DISPLAY INVISIBLE (-1900 12675);
FORCEPROP 2 LAST PATH I169
J 0
(-1450 12825);
DISPLAY 0.680851 (-1450 12825);
DISPLAY INVISIBLE (-1450 12825);
FORCEADD OFFPAGE..3
(-1850 12675);
FORCEPROP 2 LAST $XR3 85 
J 0
(-1366 12675);
DISPLAY 0.638298 (-1366 12675);
PAINT MONO (-1366 12675);
FORCEPROP 2 LAST $XR2 78 
J 0
(-1456 12675);
DISPLAY 0.638298 (-1456 12675);
PAINT MONO (-1456 12675);
FORCEPROP 2 LAST $XR1 81 
J 0
(-1546 12675);
DISPLAY 0.638298 (-1546 12675);
PAINT MONO (-1546 12675);
FORCEPROP 2 LAST $XR0 28 
J 0
(-1636 12675);
DISPLAY 0.638298 (-1636 12675);
PAINT MONO (-1636 12675);
FORCEPROP 2 LAST CDS_LIB standard
J 2
(-1850 12675);
DISPLAY INVISIBLE (-1850 12675);
FORCEPROP 1 LAST OFFPAGE TRUE
J 0
(-1525 12550);
DISPLAY 0.872340 (-1525 12550);
PAINT GREEN (-1525 12550);
DISPLAY INVISIBLE (-1525 12550);
FORCEPROP 1 LAST COMMENT_BODY TRUE
J 0
(-1900 12575);
DISPLAY 0.872340 (-1900 12575);
PAINT PEACH (-1900 12575);
DISPLAY INVISIBLE (-1900 12575);
FORCEPROP 2 LAST PATH I170
J 0
(-1350 12725);
DISPLAY 0.680851 (-1350 12725);
DISPLAY INVISIBLE (-1350 12725);
FORCEADD Q_RES..1
(-1800 13025);
FORCEPROP 1 LAST LOCATION R435
J 0
(-2150 13025);
DISPLAY 0.489362 (-2150 13025);
PAINT SKYBLUE (-2150 13025);
FORCEPROP 0 LAST $SEC 1
J 0
(-2075 13075);
DISPLAY 0.680851 (-2075 13075);
PAINT MONO (-2075 13075);
DISPLAY INVISIBLE (-2075 13075);
FORCEPROP 0 LAST CDS_SEC 1
J 0
(-2075 13075);
DISPLAY 1.021277 (-2075 13075);
DISPLAY INVISIBLE (-2075 13075);
FORCEPROP 1 LASTPIN (-1900 13025) $PN 1
J 0
(-1888 13037);
DISPLAY 0.489362 (-1888 13037);
PAINT MONO (-1888 13037);
FORCEPROP 1 LASTPIN (-1700 13025) $PN 2
J 0
(-1738 13037);
DISPLAY 0.489362 (-1738 13037);
PAINT MONO (-1738 13037);
FORCEPROP 1 LAST VALUE 0
J 2
(-1900 13025);
DISPLAY 0.489362 (-1900 13025);
PAINT SKYBLUE (-1900 13025);
FORCEPROP 1 LAST PACK_TYPE 0402LF
J 0
(-1750 12950);
DISPLAY 0.489362 (-1750 12950);
PAINT SKYBLUE (-1750 12950);
DISPLAY INVISIBLE (-1750 12950);
FORCEPROP 1 LAST TOLERANCE 5%
J 0
(-1825 12950);
DISPLAY 0.489362 (-1825 12950);
PAINT SKYBLUE (-1825 12950);
DISPLAY INVISIBLE (-1825 12950);
FORCEPROP 1 LAST MATERIAL CHIP
J 0
(-1375 12950);
DISPLAY 0.489362 (-1375 12950);
PAINT SKYBLUE (-1375 12950);
DISPLAY INVISIBLE (-1375 12950);
FORCEPROP 1 LAST WATTAGE 1/16W
J 2
(-1400 12950);
DISPLAY 0.489362 (-1400 12950);
PAINT SKYBLUE (-1400 12950);
DISPLAY INVISIBLE (-1400 12950);
FORCEPROP 2 LAST CDS_LIB pure_quanta
J 0
(-1800 13025);
DISPLAY INVISIBLE (-1800 13025);
FORCEPROP 1 LAST PATH I171
J 0
(-1850 13175);
DISPLAY 0.978723 (-1850 13175);
PAINT WHITE (-1850 13175);
DISPLAY INVISIBLE (-1850 13175);
FORCEPROP 1 LAST PART_NUMBER CS00002JB13
J 0
(-1775 13075);
DISPLAY 0.489362 (-1775 13075);
PAINT SKYBLUE (-1775 13075);
DISPLAY INVISIBLE (-1775 13075);
FORCEADD Q_RES..1
(-1800 12975);
FORCEPROP 1 LAST LOCATION R436
J 0
(-2150 12975);
DISPLAY 0.489362 (-2150 12975);
PAINT SKYBLUE (-2150 12975);
FORCEPROP 0 LAST $SEC 1
J 0
(-2075 13025);
DISPLAY 0.680851 (-2075 13025);
PAINT MONO (-2075 13025);
DISPLAY INVISIBLE (-2075 13025);
FORCEPROP 0 LAST CDS_SEC 1
J 0
(-2075 13025);
DISPLAY 1.021277 (-2075 13025);
DISPLAY INVISIBLE (-2075 13025);
FORCEPROP 1 LASTPIN (-1900 12975) $PN 1
J 0
(-1888 12987);
DISPLAY 0.489362 (-1888 12987);
PAINT MONO (-1888 12987);
FORCEPROP 1 LASTPIN (-1700 12975) $PN 2
J 0
(-1738 12987);
DISPLAY 0.489362 (-1738 12987);
PAINT MONO (-1738 12987);
FORCEPROP 1 LAST VALUE 0
J 2
(-1900 12975);
DISPLAY 0.489362 (-1900 12975);
PAINT SKYBLUE (-1900 12975);
FORCEPROP 1 LAST PACK_TYPE 0402LF
J 0
(-1750 12900);
DISPLAY 0.489362 (-1750 12900);
PAINT SKYBLUE (-1750 12900);
DISPLAY INVISIBLE (-1750 12900);
FORCEPROP 1 LAST TOLERANCE 5%
J 0
(-1825 12900);
DISPLAY 0.489362 (-1825 12900);
PAINT SKYBLUE (-1825 12900);
DISPLAY INVISIBLE (-1825 12900);
FORCEPROP 1 LAST MATERIAL CHIP
J 0
(-1375 12900);
DISPLAY 0.489362 (-1375 12900);
PAINT SKYBLUE (-1375 12900);
DISPLAY INVISIBLE (-1375 12900);
FORCEPROP 1 LAST WATTAGE 1/16W
J 2
(-1400 12900);
DISPLAY 0.489362 (-1400 12900);
PAINT SKYBLUE (-1400 12900);
DISPLAY INVISIBLE (-1400 12900);
FORCEPROP 2 LAST CDS_LIB pure_quanta
J 0
(-1800 12975);
DISPLAY INVISIBLE (-1800 12975);
FORCEPROP 1 LAST PATH I172
J 0
(-1850 13125);
DISPLAY 0.978723 (-1850 13125);
PAINT WHITE (-1850 13125);
DISPLAY INVISIBLE (-1850 13125);
FORCEPROP 1 LAST PART_NUMBER CS00002JB13
J 0
(-1775 13025);
DISPLAY 0.489362 (-1775 13025);
PAINT SKYBLUE (-1775 13025);
DISPLAY INVISIBLE (-1775 13025);
FORCEADD OFFPAGE..2
(-1425 12525);
FORCEPROP 2 LAST $XR1 81 
J 0
(-1146 12525);
DISPLAY 0.638298 (-1146 12525);
PAINT MONO (-1146 12525);
FORCEPROP 2 LAST $XR0 55 
J 0
(-1236 12525);
DISPLAY 0.638298 (-1236 12525);
PAINT MONO (-1236 12525);
FORCEPROP 2 LAST CDS_LIB standard
J 0
(-1425 12525);
DISPLAY INVISIBLE (-1425 12525);
FORCEPROP 1 LAST OFFPAGE TRUE
J 0
(-1100 12400);
DISPLAY 0.872340 (-1100 12400);
PAINT GREEN (-1100 12400);
DISPLAY INVISIBLE (-1100 12400);
FORCEPROP 1 LAST COMMENT_BODY TRUE
J 0
(-1470 12430);
DISPLAY 0.872340 (-1470 12430);
PAINT GREEN (-1470 12430);
DISPLAY INVISIBLE (-1470 12430);
FORCEPROP 2 LAST PATH I173
J 0
(-1125 12575);
DISPLAY 0.680851 (-1125 12575);
DISPLAY INVISIBLE (-1125 12575);
FORCEADD OFFPAGE..2
(-600 11175);
FORCEPROP 2 LAST $XR0 131 
J 0
(-411 11175);
DISPLAY 0.638298 (-411 11175);
PAINT MONO (-411 11175);
FORCEPROP 2 LAST CDS_LIB standard
J 0
(-600 11175);
DISPLAY INVISIBLE (-600 11175);
FORCEPROP 1 LAST OFFPAGE TRUE
J 0
(-275 11050);
DISPLAY 0.872340 (-275 11050);
PAINT GREEN (-275 11050);
DISPLAY INVISIBLE (-275 11050);
FORCEPROP 1 LAST COMMENT_BODY TRUE
J 0
(-645 11080);
DISPLAY 0.872340 (-645 11080);
PAINT GREEN (-645 11080);
DISPLAY INVISIBLE (-645 11080);
FORCEPROP 2 LAST PATH I174
J 0
(-425 11250);
DISPLAY 0.680851 (-425 11250);
DISPLAY INVISIBLE (-425 11250);
FORCEADD OFFPAGE..2
(-600 11225);
FORCEPROP 2 LAST $XR0 131 
J 0
(-411 11225);
DISPLAY 0.638298 (-411 11225);
PAINT MONO (-411 11225);
FORCEPROP 2 LAST CDS_LIB standard
J 0
(-600 11225);
DISPLAY INVISIBLE (-600 11225);
FORCEPROP 1 LAST OFFPAGE TRUE
J 0
(-275 11100);
DISPLAY 0.872340 (-275 11100);
PAINT GREEN (-275 11100);
DISPLAY INVISIBLE (-275 11100);
FORCEPROP 1 LAST COMMENT_BODY TRUE
J 0
(-645 11130);
DISPLAY 0.872340 (-645 11130);
PAINT GREEN (-645 11130);
DISPLAY INVISIBLE (-645 11130);
FORCEPROP 2 LAST PATH I175
J 0
(-425 11300);
DISPLAY 0.680851 (-425 11300);
DISPLAY INVISIBLE (-425 11300);
FORCEADD OFFPAGE..2
(-600 11075);
FORCEPROP 2 LAST $XR0 122 
J 0
(-411 11075);
DISPLAY 0.638298 (-411 11075);
PAINT MONO (-411 11075);
FORCEPROP 2 LAST CDS_LIB standard
J 0
(-600 11075);
DISPLAY INVISIBLE (-600 11075);
FORCEPROP 1 LAST OFFPAGE TRUE
J 0
(-275 10950);
DISPLAY 0.872340 (-275 10950);
PAINT GREEN (-275 10950);
DISPLAY INVISIBLE (-275 10950);
FORCEPROP 1 LAST COMMENT_BODY TRUE
J 0
(-645 10980);
DISPLAY 0.872340 (-645 10980);
PAINT GREEN (-645 10980);
DISPLAY INVISIBLE (-645 10980);
FORCEPROP 2 LAST PATH I176
J 0
(-400 11125);
DISPLAY 0.680851 (-400 11125);
DISPLAY INVISIBLE (-400 11125);
FORCEADD OFFPAGE..2
(-600 11375);
FORCEPROP 2 LAST $XR0 131 
J 0
(-411 11375);
DISPLAY 0.638298 (-411 11375);
PAINT MONO (-411 11375);
FORCEPROP 2 LAST CDS_LIB standard
J 0
(-600 11375);
DISPLAY INVISIBLE (-600 11375);
FORCEPROP 1 LAST OFFPAGE TRUE
J 0
(-275 11250);
DISPLAY 0.872340 (-275 11250);
PAINT GREEN (-275 11250);
DISPLAY INVISIBLE (-275 11250);
FORCEPROP 1 LAST COMMENT_BODY TRUE
J 0
(-645 11280);
DISPLAY 0.872340 (-645 11280);
PAINT GREEN (-645 11280);
DISPLAY INVISIBLE (-645 11280);
FORCEPROP 2 LAST PATH I177
J 0
(-425 11450);
DISPLAY 0.680851 (-425 11450);
DISPLAY INVISIBLE (-425 11450);
FORCEADD OFFPAGE..2
(-600 11325);
FORCEPROP 2 LAST $XR0 131 
J 0
(-411 11325);
DISPLAY 0.638298 (-411 11325);
PAINT MONO (-411 11325);
FORCEPROP 2 LAST CDS_LIB standard
J 0
(-600 11325);
DISPLAY INVISIBLE (-600 11325);
FORCEPROP 1 LAST OFFPAGE TRUE
J 0
(-275 11200);
DISPLAY 0.872340 (-275 11200);
PAINT GREEN (-275 11200);
DISPLAY INVISIBLE (-275 11200);
FORCEPROP 1 LAST COMMENT_BODY TRUE
J 0
(-645 11230);
DISPLAY 0.872340 (-645 11230);
PAINT GREEN (-645 11230);
DISPLAY INVISIBLE (-645 11230);
FORCEPROP 2 LAST PATH I178
J 0
(-425 11400);
DISPLAY 0.680851 (-425 11400);
DISPLAY INVISIBLE (-425 11400);
FORCEADD OFFPAGE..2
(-600 11475);
FORCEPROP 2 LAST $XR0 131 
J 0
(-411 11475);
DISPLAY 0.638298 (-411 11475);
PAINT MONO (-411 11475);
FORCEPROP 2 LAST CDS_LIB standard
J 0
(-600 11475);
DISPLAY INVISIBLE (-600 11475);
FORCEPROP 1 LAST OFFPAGE TRUE
J 0
(-275 11350);
DISPLAY 0.872340 (-275 11350);
PAINT GREEN (-275 11350);
DISPLAY INVISIBLE (-275 11350);
FORCEPROP 1 LAST COMMENT_BODY TRUE
J 0
(-645 11380);
DISPLAY 0.872340 (-645 11380);
PAINT GREEN (-645 11380);
DISPLAY INVISIBLE (-645 11380);
FORCEPROP 2 LAST PATH I179
J 0
(-425 11550);
DISPLAY 0.680851 (-425 11550);
DISPLAY INVISIBLE (-425 11550);
FORCEADD OFFPAGE..2
R 2
(-8750 8725);
FORCEPROP 2 LAST $XR2 85 
J 0
(-9154 8725);
DISPLAY 0.638298 (-9154 8725);
PAINT MONO (-9154 8725);
FORCEPROP 2 LAST $XR1 81 
J 0
(-9064 8725);
DISPLAY 0.638298 (-9064 8725);
PAINT MONO (-9064 8725);
FORCEPROP 2 LAST $XR0 28 
J 0
(-8974 8725);
DISPLAY 0.638298 (-8974 8725);
PAINT MONO (-8974 8725);
FORCEPROP 2 LAST CDS_LIB standard
J 0
(-8750 8725);
DISPLAY INVISIBLE (-8750 8725);
FORCEPROP 1 LAST OFFPAGE TRUE
J 2
(-9075 8600);
DISPLAY 0.872340 (-9075 8600);
PAINT GREEN (-9075 8600);
DISPLAY INVISIBLE (-9075 8600);
FORCEPROP 1 LAST COMMENT_BODY TRUE
J 2
(-8705 8630);
DISPLAY 0.872340 (-8705 8630);
PAINT GREEN (-8705 8630);
DISPLAY INVISIBLE (-8705 8630);
FORCEPROP 2 LAST PATH I18
J 0
(-8950 8775);
DISPLAY 0.680851 (-8950 8775);
DISPLAY INVISIBLE (-8950 8775);
FORCEADD OFFPAGE..2
(-600 11525);
FORCEPROP 2 LAST $XR0 131 
J 0
(-411 11525);
DISPLAY 0.638298 (-411 11525);
PAINT MONO (-411 11525);
FORCEPROP 2 LAST CDS_LIB standard
J 0
(-600 11525);
DISPLAY INVISIBLE (-600 11525);
FORCEPROP 1 LAST OFFPAGE TRUE
J 0
(-275 11400);
DISPLAY 0.872340 (-275 11400);
PAINT GREEN (-275 11400);
DISPLAY INVISIBLE (-275 11400);
FORCEPROP 1 LAST COMMENT_BODY TRUE
J 0
(-645 11430);
DISPLAY 0.872340 (-645 11430);
PAINT GREEN (-645 11430);
DISPLAY INVISIBLE (-645 11430);
FORCEPROP 2 LAST PATH I180
J 0
(-425 11600);
DISPLAY 0.680851 (-425 11600);
DISPLAY INVISIBLE (-425 11600);
FORCEADD OFFPAGE..2
(-600 11625);
FORCEPROP 2 LAST $XR0 131 
J 0
(-411 11625);
DISPLAY 0.638298 (-411 11625);
PAINT MONO (-411 11625);
FORCEPROP 2 LAST CDS_LIB standard
J 0
(-600 11625);
DISPLAY INVISIBLE (-600 11625);
FORCEPROP 1 LAST OFFPAGE TRUE
J 0
(-275 11500);
DISPLAY 0.872340 (-275 11500);
PAINT GREEN (-275 11500);
DISPLAY INVISIBLE (-275 11500);
FORCEPROP 1 LAST COMMENT_BODY TRUE
J 0
(-645 11530);
DISPLAY 0.872340 (-645 11530);
PAINT GREEN (-645 11530);
DISPLAY INVISIBLE (-645 11530);
FORCEPROP 2 LAST PATH I181
J 0
(-425 11700);
DISPLAY 0.680851 (-425 11700);
DISPLAY INVISIBLE (-425 11700);
FORCEADD OFFPAGE..2
(-600 11675);
FORCEPROP 2 LAST $XR0 131 
J 0
(-411 11675);
DISPLAY 0.638298 (-411 11675);
PAINT MONO (-411 11675);
FORCEPROP 2 LAST CDS_LIB standard
J 0
(-600 11675);
DISPLAY INVISIBLE (-600 11675);
FORCEPROP 1 LAST OFFPAGE TRUE
J 0
(-275 11550);
DISPLAY 0.872340 (-275 11550);
PAINT GREEN (-275 11550);
DISPLAY INVISIBLE (-275 11550);
FORCEPROP 1 LAST COMMENT_BODY TRUE
J 0
(-645 11580);
DISPLAY 0.872340 (-645 11580);
PAINT GREEN (-645 11580);
DISPLAY INVISIBLE (-645 11580);
FORCEPROP 2 LAST PATH I182
J 0
(-425 11750);
DISPLAY 0.680851 (-425 11750);
DISPLAY INVISIBLE (-425 11750);
FORCEADD OFFPAGE..2
(-600 11775);
FORCEPROP 2 LAST $XR0 150 
J 0
(-411 11775);
DISPLAY 0.638298 (-411 11775);
PAINT MONO (-411 11775);
FORCEPROP 2 LAST CDS_LIB standard
J 0
(-600 11775);
DISPLAY INVISIBLE (-600 11775);
FORCEPROP 1 LAST OFFPAGE TRUE
J 0
(-275 11650);
DISPLAY 0.872340 (-275 11650);
PAINT GREEN (-275 11650);
DISPLAY INVISIBLE (-275 11650);
FORCEPROP 1 LAST COMMENT_BODY TRUE
J 0
(-645 11680);
DISPLAY 0.872340 (-645 11680);
PAINT GREEN (-645 11680);
DISPLAY INVISIBLE (-645 11680);
FORCEPROP 2 LAST PATH I183
J 0
(-425 11850);
DISPLAY 0.680851 (-425 11850);
DISPLAY INVISIBLE (-425 11850);
FORCEADD OFFPAGE..2
(-600 11825);
FORCEPROP 2 LAST $XR0 150 
J 0
(-411 11825);
DISPLAY 0.638298 (-411 11825);
PAINT MONO (-411 11825);
FORCEPROP 2 LAST CDS_LIB standard
J 0
(-600 11825);
DISPLAY INVISIBLE (-600 11825);
FORCEPROP 1 LAST OFFPAGE TRUE
J 0
(-275 11700);
DISPLAY 0.872340 (-275 11700);
PAINT GREEN (-275 11700);
DISPLAY INVISIBLE (-275 11700);
FORCEPROP 1 LAST COMMENT_BODY TRUE
J 0
(-645 11730);
DISPLAY 0.872340 (-645 11730);
PAINT GREEN (-645 11730);
DISPLAY INVISIBLE (-645 11730);
FORCEPROP 2 LAST PATH I184
J 0
(-425 11900);
DISPLAY 0.680851 (-425 11900);
DISPLAY INVISIBLE (-425 11900);
FORCEADD OFFPAGE..1
R 2
(-600 12425);
FORCEPROP 2 LAST $XR1 55 
J 0
(-294 12425);
DISPLAY 0.638298 (-294 12425);
PAINT MONO (-294 12425);
FORCEPROP 2 LAST $XR0 155 
J 0
(-414 12425);
DISPLAY 0.638298 (-414 12425);
PAINT MONO (-414 12425);
FORCEPROP 2 LAST CDS_LIB standard
J 2
(-600 12425);
DISPLAY INVISIBLE (-600 12425);
FORCEPROP 1 LAST OFFPAGE TRUE
J 2
(-925 12300);
DISPLAY 0.872340 (-925 12300);
PAINT GREEN (-925 12300);
DISPLAY INVISIBLE (-925 12300);
FORCEPROP 1 LAST COMMENT_BODY TRUE
J 2
(-725 12325);
DISPLAY 0.872340 (-725 12325);
PAINT GREEN (-725 12325);
DISPLAY INVISIBLE (-725 12325);
FORCEPROP 2 LAST PATH I185
J 0
(-275 12475);
DISPLAY 0.680851 (-275 12475);
DISPLAY INVISIBLE (-275 12475);
FORCEADD OFFPAGE..2
(-850 13025);
FORCEPROP 2 LAST $XR0 55 
J 0
(-661 13025);
DISPLAY 0.638298 (-661 13025);
PAINT MONO (-661 13025);
FORCEPROP 2 LAST CDS_LIB standard
J 0
(-850 13025);
DISPLAY INVISIBLE (-850 13025);
FORCEPROP 1 LAST OFFPAGE TRUE
J 0
(-525 12900);
DISPLAY 0.872340 (-525 12900);
PAINT GREEN (-525 12900);
DISPLAY INVISIBLE (-525 12900);
FORCEPROP 1 LAST COMMENT_BODY TRUE
J 0
(-895 12930);
DISPLAY 0.872340 (-895 12930);
PAINT GREEN (-895 12930);
DISPLAY INVISIBLE (-895 12930);
FORCEPROP 2 LAST PATH I186
J 0
(-650 13075);
DISPLAY 0.680851 (-650 13075);
DISPLAY INVISIBLE (-650 13075);
FORCEADD OFFPAGE..2
(-850 12975);
FORCEPROP 2 LAST $XR0 55 
J 0
(-661 12975);
DISPLAY 0.638298 (-661 12975);
PAINT MONO (-661 12975);
FORCEPROP 2 LAST CDS_LIB standard
J 0
(-850 12975);
DISPLAY INVISIBLE (-850 12975);
FORCEPROP 1 LAST OFFPAGE TRUE
J 0
(-525 12850);
DISPLAY 0.872340 (-525 12850);
PAINT GREEN (-525 12850);
DISPLAY INVISIBLE (-525 12850);
FORCEPROP 1 LAST COMMENT_BODY TRUE
J 0
(-895 12880);
DISPLAY 0.872340 (-895 12880);
PAINT GREEN (-895 12880);
DISPLAY INVISIBLE (-895 12880);
FORCEPROP 2 LAST PATH I187
J 0
(-650 13025);
DISPLAY 0.680851 (-650 13025);
DISPLAY INVISIBLE (-650 13025);
FORCEADD GENOA_SP5..21
(-4350 11375);
FORCEPROP 1 LAST LOCATION U25
J 0
(-5445 13402);
DISPLAY 0.489362 (-5445 13402);
PAINT SKYBLUE (-5445 13402);
FORCEPROP 0 LAST $SEC 21
J 0
(-5425 13450);
DISPLAY 0.680851 (-5425 13450);
PAINT MONO (-5425 13450);
DISPLAY INVISIBLE (-5425 13450);
FORCEPROP 0 LAST CDS_SEC 21
J 0
(-5450 13075);
DISPLAY 1.021277 (-5450 13075);
DISPLAY INVISIBLE (-5450 13075);
FORCEPROP 0 LASTPIN (-5600 10375) $PN DE36
J 2
(-5610 10385);
DISPLAY 0.489362 (-5610 10385);
PAINT MONO (-5610 10385);
FORCEPROP 0 LASTPIN (-5600 10325) $PN DF36
J 2
(-5610 10335);
DISPLAY 0.489362 (-5610 10335);
PAINT MONO (-5610 10335);
FORCEPROP 0 LASTPIN (-5600 10275) $PN DF40
J 2
(-5610 10285);
DISPLAY 0.489362 (-5610 10285);
PAINT MONO (-5610 10285);
FORCEPROP 0 LASTPIN (-5600 10225) $PN DE40
J 2
(-5610 10235);
DISPLAY 0.489362 (-5610 10235);
PAINT MONO (-5610 10235);
FORCEPROP 0 LASTPIN (-5600 9625) $PN DH4
J 2
(-5610 9635);
DISPLAY 0.489362 (-5610 9635);
PAINT MONO (-5610 9635);
FORCEPROP 0 LASTPIN (-5600 10075) $PN DF33
J 2
(-5610 10085);
DISPLAY 0.489362 (-5610 10085);
PAINT MONO (-5610 10085);
FORCEPROP 0 LASTPIN (-5600 10025) $PN DE32
J 2
(-5610 10035);
DISPLAY 0.489362 (-5610 10035);
PAINT MONO (-5610 10035);
FORCEPROP 0 LASTPIN (-5600 9975) $PN DG11
J 2
(-5610 9985);
DISPLAY 0.489362 (-5610 9985);
PAINT MONO (-5610 9985);
FORCEPROP 0 LASTPIN (-5600 9925) $PN DJ29
J 2
(-5610 9935);
DISPLAY 0.489362 (-5610 9935);
PAINT MONO (-5610 9935);
FORCEPROP 0 LASTPIN (-5600 9875) $PN DH30
J 2
(-5610 9885);
DISPLAY 0.489362 (-5610 9885);
PAINT MONO (-5610 9885);
FORCEPROP 0 LASTPIN (-5600 9825) $PN DE30
J 2
(-5610 9835);
DISPLAY 0.489362 (-5610 9835);
PAINT MONO (-5610 9835);
FORCEPROP 0 LASTPIN (-5600 9775) $PN DF31
J 2
(-5610 9785);
DISPLAY 0.489362 (-5610 9785);
PAINT MONO (-5610 9785);
FORCEPROP 0 LASTPIN (-5600 9725) $PN DG31
J 2
(-5610 9735);
DISPLAY 0.489362 (-5610 9735);
PAINT MONO (-5610 9735);
FORCEPROP 0 LASTPIN (-5600 9675) $PN DG32
J 2
(-5610 9685);
DISPLAY 0.489362 (-5610 9685);
PAINT MONO (-5610 9685);
FORCEPROP 0 LASTPIN (-5600 10175) $PN DH16
J 2
(-5610 10185);
DISPLAY 0.489362 (-5610 10185);
PAINT MONO (-5610 10185);
FORCEPROP 0 LASTPIN (-5600 10125) $PN DH15
J 2
(-5610 10135);
DISPLAY 0.489362 (-5610 10135);
PAINT MONO (-5610 10135);
FORCEPROP 0 LASTPIN (-3100 9875) $PN A14
J 0
(-3090 9885);
DISPLAY 0.489362 (-3090 9885);
PAINT MONO (-3090 9885);
FORCEPROP 0 LASTPIN (-3100 9825) $PN C14
J 0
(-3090 9835);
DISPLAY 0.489362 (-3090 9835);
PAINT MONO (-3090 9835);
FORCEPROP 0 LASTPIN (-3100 9775) $PN A13
J 0
(-3090 9785);
DISPLAY 0.489362 (-3090 9785);
PAINT MONO (-3090 9785);
FORCEPROP 0 LASTPIN (-3100 9725) $PN B16
J 0
(-3090 9735);
DISPLAY 0.489362 (-3090 9735);
PAINT MONO (-3090 9735);
FORCEPROP 0 LASTPIN (-3100 12325) $PN B63
J 0
(-3090 12335);
DISPLAY 0.489362 (-3090 12335);
PAINT MONO (-3090 12335);
FORCEPROP 0 LASTPIN (-5600 11775) $PN DJ35
J 2
(-5610 11785);
DISPLAY 0.489362 (-5610 11785);
PAINT MONO (-5610 11785);
FORCEPROP 0 LASTPIN (-3100 11775) $PN A7
J 0
(-3090 11785);
DISPLAY 0.489362 (-3090 11785);
PAINT MONO (-3090 11785);
FORCEPROP 0 LASTPIN (-3100 11825) $PN A8
J 0
(-3090 11835);
DISPLAY 0.489362 (-3090 11835);
PAINT MONO (-3090 11835);
FORCEPROP 0 LASTPIN (-3100 11625) $PN C6
J 0
(-3090 11635);
DISPLAY 0.489362 (-3090 11635);
PAINT MONO (-3090 11635);
FORCEPROP 0 LASTPIN (-3100 11675) $PN B6
J 0
(-3090 11685);
DISPLAY 0.489362 (-3090 11685);
PAINT MONO (-3090 11685);
FORCEPROP 0 LASTPIN (-3100 11475) $PN A11
J 0
(-3090 11485);
DISPLAY 0.489362 (-3090 11485);
PAINT MONO (-3090 11485);
FORCEPROP 0 LASTPIN (-3100 11525) $PN A10
J 0
(-3090 11535);
DISPLAY 0.489362 (-3090 11535);
PAINT MONO (-3090 11535);
FORCEPROP 0 LASTPIN (-3100 11325) $PN C12
J 0
(-3090 11335);
DISPLAY 0.489362 (-3090 11335);
PAINT MONO (-3090 11335);
FORCEPROP 0 LASTPIN (-3100 11375) $PN B12
J 0
(-3090 11385);
DISPLAY 0.489362 (-3090 11385);
PAINT MONO (-3090 11385);
FORCEPROP 0 LASTPIN (-3100 11175) $PN C9
J 0
(-3090 11185);
DISPLAY 0.489362 (-3090 11185);
PAINT MONO (-3090 11185);
FORCEPROP 0 LASTPIN (-3100 11225) $PN B9
J 0
(-3090 11235);
DISPLAY 0.489362 (-3090 11235);
PAINT MONO (-3090 11235);
FORCEPROP 0 LASTPIN (-3100 11025) $PN DJ42
J 0
(-3090 11035);
DISPLAY 0.489362 (-3090 11035);
PAINT MONO (-3090 11035);
FORCEPROP 0 LASTPIN (-3100 11075) $PN DJ41
J 0
(-3090 11085);
DISPLAY 0.489362 (-3090 11085);
PAINT MONO (-3090 11085);
FORCEPROP 0 LASTPIN (-3100 10875) $PN DJ44
J 0
(-3090 10885);
DISPLAY 0.489362 (-3090 10885);
PAINT MONO (-3090 10885);
FORCEPROP 0 LASTPIN (-3100 10925) $PN DJ45
J 0
(-3090 10935);
DISPLAY 0.489362 (-3090 10935);
PAINT MONO (-3090 10935);
FORCEPROP 0 LASTPIN (-3100 10725) $PN DJ54
J 0
(-3090 10735);
DISPLAY 0.489362 (-3090 10735);
PAINT MONO (-3090 10735);
FORCEPROP 0 LASTPIN (-3100 10775) $PN DJ53
J 0
(-3090 10785);
DISPLAY 0.489362 (-3090 10785);
PAINT MONO (-3090 10785);
FORCEPROP 0 LASTPIN (-3100 10575) $PN DJ47
J 0
(-3090 10585);
DISPLAY 0.489362 (-3090 10585);
PAINT MONO (-3090 10585);
FORCEPROP 0 LASTPIN (-3100 10625) $PN DJ48
J 0
(-3090 10635);
DISPLAY 0.489362 (-3090 10635);
PAINT MONO (-3090 10635);
FORCEPROP 0 LASTPIN (-3100 10425) $PN DJ50
J 0
(-3090 10435);
DISPLAY 0.489362 (-3090 10435);
PAINT MONO (-3090 10435);
FORCEPROP 0 LASTPIN (-3100 10475) $PN DJ51
J 0
(-3090 10485);
DISPLAY 0.489362 (-3090 10485);
PAINT MONO (-3090 10485);
FORCEPROP 0 LASTPIN (-5600 10925) $PN DG12
J 2
(-5610 10935);
DISPLAY 0.489362 (-5610 10935);
PAINT MONO (-5610 10935);
FORCEPROP 0 LASTPIN (-5600 10875) $PN DH12
J 2
(-5610 10885);
DISPLAY 0.489362 (-5610 10885);
PAINT MONO (-5610 10885);
FORCEPROP 0 LASTPIN (-5600 10825) $PN DJ21
J 2
(-5610 10835);
DISPLAY 0.489362 (-5610 10835);
PAINT MONO (-5610 10835);
FORCEPROP 0 LASTPIN (-5600 10775) $PN DJ20
J 2
(-5610 10785);
DISPLAY 0.489362 (-5610 10785);
PAINT MONO (-5610 10785);
FORCEPROP 0 LASTPIN (-5600 11325) $PN A71
J 2
(-5610 11335);
DISPLAY 0.489362 (-5610 11335);
PAINT MONO (-5610 11335);
FORCEPROP 0 LASTPIN (-5600 11275) $PN B71
J 2
(-5610 11285);
DISPLAY 0.489362 (-5610 11285);
PAINT MONO (-5610 11285);
FORCEPROP 0 LASTPIN (-5600 11225) $PN C7
J 2
(-5610 11235);
DISPLAY 0.489362 (-5610 11235);
PAINT MONO (-5610 11235);
FORCEPROP 0 LASTPIN (-5600 11175) $PN A5
J 2
(-5610 11185);
DISPLAY 0.489362 (-5610 11185);
PAINT MONO (-5610 11185);
FORCEPROP 0 LASTPIN (-5600 11125) $PN C72
J 2
(-5610 11135);
DISPLAY 0.489362 (-5610 11135);
PAINT MONO (-5610 11135);
FORCEPROP 0 LASTPIN (-5600 11075) $PN B72
J 2
(-5610 11085);
DISPLAY 0.489362 (-5610 11085);
PAINT MONO (-5610 11085);
FORCEPROP 0 LASTPIN (-5600 11025) $PN A4
J 2
(-5610 11035);
DISPLAY 0.489362 (-5610 11035);
PAINT MONO (-5610 11035);
FORCEPROP 0 LASTPIN (-5600 10975) $PN B4
J 2
(-5610 10985);
DISPLAY 0.489362 (-5610 10985);
PAINT MONO (-5610 10985);
FORCEPROP 0 LASTPIN (-5600 11575) $PN DJ31
J 2
(-5610 11585);
DISPLAY 0.489362 (-5610 11585);
PAINT MONO (-5610 11585);
FORCEPROP 0 LASTPIN (-3100 12225) $PN B64
J 0
(-3090 12235);
DISPLAY 0.489362 (-3090 12235);
PAINT MONO (-3090 12235);
FORCEPROP 0 LASTPIN (-3100 12075) $PN D18
J 0
(-3090 12085);
DISPLAY 0.489362 (-3090 12085);
PAINT MONO (-3090 12085);
FORCEPROP 0 LASTPIN (-3100 12025) $PN DG36
J 0
(-3090 12035);
DISPLAY 0.489362 (-3090 12035);
PAINT MONO (-3090 12035);
FORCEPROP 0 LASTPIN (-5600 12525) $PN DH7
J 2
(-5610 12535);
DISPLAY 0.489362 (-5610 12535);
PAINT MONO (-5610 12535);
FORCEPROP 0 LASTPIN (-5600 12325) $PN DJ8
J 2
(-5610 12335);
DISPLAY 0.489362 (-5610 12335);
PAINT MONO (-5610 12335);
FORCEPROP 0 LASTPIN (-3100 12525) $PN DH36
J 0
(-3090 12535);
DISPLAY 0.489362 (-3090 12535);
PAINT MONO (-3090 12535);
FORCEPROP 0 LASTPIN (-3100 12675) $PN D69
J 0
(-3090 12685);
DISPLAY 0.489362 (-3090 12685);
PAINT MONO (-3090 12685);
FORCEPROP 0 LASTPIN (-3100 12975) $PN A20
J 0
(-3090 12985);
DISPLAY 0.489362 (-3090 12985);
PAINT MONO (-3090 12985);
FORCEPROP 0 LASTPIN (-3100 13025) $PN A19
J 0
(-3090 13035);
DISPLAY 0.489362 (-3090 13035);
PAINT MONO (-3090 13035);
FORCEPROP 0 LASTPIN (-3100 12775) $PN B67
J 0
(-3090 12785);
DISPLAY 0.489362 (-3090 12785);
PAINT MONO (-3090 12785);
FORCEPROP 0 LASTPIN (-5600 12425) $PN DG10
J 2
(-5610 12435);
DISPLAY 0.489362 (-5610 12435);
PAINT MONO (-5610 12435);
FORCEPROP 0 LASTPIN (-3100 12875) $PN DH9
J 0
(-3090 12885);
DISPLAY 0.489362 (-3090 12885);
PAINT MONO (-3090 12885);
FORCEPROP 0 LASTPIN (-3100 10075) $PN B14
J 0
(-3090 10085);
DISPLAY 0.489362 (-3090 10085);
PAINT MONO (-3090 10085);
FORCEPROP 0 LASTPIN (-3100 10025) $PN D14
J 0
(-3090 10035);
DISPLAY 0.489362 (-3090 10035);
PAINT MONO (-3090 10035);
FORCEPROP 0 LASTPIN (-5600 10525) $PN D15
J 2
(-5610 10535);
DISPLAY 0.489362 (-5610 10535);
PAINT MONO (-5610 10535);
FORCEPROP 0 LASTPIN (-5600 10475) $PN B15
J 2
(-5610 10485);
DISPLAY 0.489362 (-5610 10485);
PAINT MONO (-5610 10485);
FORCEPROP 0 LASTPIN (-5600 12625) $PN DJ5
J 2
(-5610 12635);
DISPLAY 0.489362 (-5610 12635);
PAINT MONO (-5610 12635);
FORCEPROP 0 LASTPIN (-5600 12675) $PN DG4
J 2
(-5610 12685);
DISPLAY 0.489362 (-5610 12685);
PAINT MONO (-5610 12685);
FORCEPROP 0 LASTPIN (-5600 10625) $PN DJ11
J 2
(-5610 10635);
DISPLAY 0.489362 (-5610 10635);
PAINT MONO (-5610 10635);
FORCEPROP 0 LASTPIN (-5600 12475) $PN DH6
J 2
(-5610 12485);
DISPLAY 0.489362 (-5610 12485);
PAINT MONO (-5610 12485);
FORCEPROP 0 LASTPIN (-3100 12425) $PN DJ10
J 0
(-3090 12435);
DISPLAY 0.489362 (-3090 12435);
PAINT MONO (-3090 12435);
FORCEPROP 0 LASTPIN (-5600 11975) $PN DJ14
J 2
(-5610 11985);
DISPLAY 0.489362 (-5610 11985);
PAINT MONO (-5610 11985);
FORCEPROP 0 LASTPIN (-5600 11925) $PN DJ13
J 2
(-5610 11935);
DISPLAY 0.489362 (-5610 11935);
PAINT MONO (-5610 11935);
FORCEPROP 0 LASTPIN (-5600 12175) $PN DJ17
J 2
(-5610 12185);
DISPLAY 0.489362 (-5610 12185);
PAINT MONO (-5610 12185);
FORCEPROP 0 LASTPIN (-5600 12125) $PN DJ16
J 2
(-5610 12135);
DISPLAY 0.489362 (-5610 12135);
PAINT MONO (-5610 12135);
FORCEPROP 2 LAST PART_TYPE SMLF
J 0
(-5450 13025);
DISPLAY 1.021277 (-5450 13025);
FORCEPROP 2 LAST VALUE SOCKET6096_13568-001
J 0
(-5450 12925);
DISPLAY 0.489362 (-5450 12925);
PAINT SKYBLUE (-5450 12925);
FORCEPROP 1 LAST MATERIAL IO
J 0
(-5445 13208);
DISPLAY 0.489362 (-5445 13208);
PAINT SKYBLUE (-5445 13208);
FORCEPROP 2 LAST CDS_LIB pure_quanta
J 0
(-4350 11375);
DISPLAY INVISIBLE (-4350 11375);
FORCEPROP 1 LAST CDS_LMAN_SYM_OUTLINE -1100,1800,1100,-1800
J 0
(-4350 11375);
DISPLAY 0.468085 (-4350 11375);
PAINT GREEN (-4350 11375);
DISPLAY INVISIBLE (-4350 11375);
FORCEPROP 1 LAST NEEDS_NO_SIZE TRUE
J 0
(-4350 11375);
DISPLAY 0.723404 (-4350 11375);
PAINT GREEN (-4350 11375);
DISPLAY INVISIBLE (-4350 11375);
FORCEPROP 1 LAST PATH I188
J 0
(-4350 11375);
DISPLAY 0.723404 (-4350 11375);
PAINT GREEN (-4350 11375);
DISPLAY INVISIBLE (-4350 11375);
FORCEPROP 1 LAST PART_NUMBER DGA^6000030
J 0
(-5445 13307);
DISPLAY 0.489362 (-5445 13307);
PAINT SKYBLUE (-5445 13307);
DISPLAY INVISIBLE (-5445 13307);
FORCEADD OFFPAGE..2
(-600 10925);
FORCEPROP 2 LAST $XR0 145 
J 0
(-411 10925);
DISPLAY 0.638298 (-411 10925);
PAINT MONO (-411 10925);
FORCEPROP 2 LAST CDS_LIB standard
J 0
(-600 10925);
DISPLAY INVISIBLE (-600 10925);
FORCEPROP 1 LAST OFFPAGE TRUE
J 0
(-275 10800);
DISPLAY 0.872340 (-275 10800);
PAINT GREEN (-275 10800);
DISPLAY INVISIBLE (-275 10800);
FORCEPROP 1 LAST COMMENT_BODY TRUE
J 0
(-645 10830);
DISPLAY 0.872340 (-645 10830);
PAINT GREEN (-645 10830);
DISPLAY INVISIBLE (-645 10830);
FORCEPROP 2 LAST PATH I189
J 0
(-425 11000);
DISPLAY 0.680851 (-425 11000);
DISPLAY INVISIBLE (-425 11000);
FORCEADD OFFPAGE..2
R 2
(-8750 8775);
FORCEPROP 2 LAST $XR1 28 
J 0
(-9064 8775);
DISPLAY 0.638298 (-9064 8775);
PAINT MONO (-9064 8775);
FORCEPROP 2 LAST $XR0 81 
J 0
(-8974 8775);
DISPLAY 0.638298 (-8974 8775);
PAINT MONO (-8974 8775);
FORCEPROP 2 LAST CDS_LIB standard
J 0
(-8750 8775);
DISPLAY INVISIBLE (-8750 8775);
FORCEPROP 1 LAST OFFPAGE TRUE
J 2
(-9075 8650);
DISPLAY 0.872340 (-9075 8650);
PAINT GREEN (-9075 8650);
DISPLAY INVISIBLE (-9075 8650);
FORCEPROP 1 LAST COMMENT_BODY TRUE
J 2
(-8705 8680);
DISPLAY 0.872340 (-8705 8680);
PAINT GREEN (-8705 8680);
DISPLAY INVISIBLE (-8705 8680);
FORCEPROP 2 LAST PATH I19
J 0
(-8950 8825);
DISPLAY 0.680851 (-8950 8825);
DISPLAY INVISIBLE (-8950 8825);
FORCEADD OFFPAGE..2
(-600 10875);
FORCEPROP 2 LAST $XR0 145 
J 0
(-411 10875);
DISPLAY 0.638298 (-411 10875);
PAINT MONO (-411 10875);
FORCEPROP 2 LAST CDS_LIB standard
J 0
(-600 10875);
DISPLAY INVISIBLE (-600 10875);
FORCEPROP 1 LAST OFFPAGE TRUE
J 0
(-275 10750);
DISPLAY 0.872340 (-275 10750);
PAINT GREEN (-275 10750);
DISPLAY INVISIBLE (-275 10750);
FORCEPROP 1 LAST COMMENT_BODY TRUE
J 0
(-645 10780);
DISPLAY 0.872340 (-645 10780);
PAINT GREEN (-645 10780);
DISPLAY INVISIBLE (-645 10780);
FORCEPROP 2 LAST PATH I190
J 0
(-425 10950);
DISPLAY 0.680851 (-425 10950);
DISPLAY INVISIBLE (-425 10950);
FORCEADD Q_RES..1
(-2000 10925);
FORCEPROP 1 LAST LOCATION R4303
J 0
(-2150 10925);
DISPLAY 0.510638 (-2150 10925);
FORCEPROP 0 LAST $SEC 1
J 0
(-1575 10950);
DISPLAY 0.680851 (-1575 10950);
PAINT MONO (-1575 10950);
DISPLAY INVISIBLE (-1575 10950);
FORCEPROP 0 LAST CDS_SEC 1
J 0
(-1575 10950);
DISPLAY 0.680851 (-1575 10950);
DISPLAY INVISIBLE (-1575 10950);
FORCEPROP 1 LASTPIN (-2100 10925) $PN 1
J 0
(-2088 10937);
DISPLAY 0.787234 (-2088 10937);
PAINT MONO (-2088 10937);
FORCEPROP 1 LASTPIN (-1900 10925) $PN 2
J 0
(-1938 10937);
DISPLAY 0.787234 (-1938 10937);
PAINT MONO (-1938 10937);
FORCEPROP 1 LAST VALUE 0
J 2
(-1875 10925);
DISPLAY 0.510638 (-1875 10925);
FORCEPROP 1 LAST PACK_TYPE 0402LF
J 0
(-2325 10925);
DISPLAY 0.510638 (-2325 10925);
FORCEPROP 1 LAST WATTAGE 1/16W
J 2
(-1575 10925);
DISPLAY 0.510638 (-1575 10925);
FORCEPROP 1 LAST TOLERANCE 5%
J 0
(-1825 10925);
DISPLAY 0.510638 (-1825 10925);
FORCEPROP 2 LAST CDS_LIB pure_quanta
J 0
(-2000 10925);
DISPLAY INVISIBLE (-2000 10925);
FORCEPROP 1 LAST MATERIAL CHIP
J 0
(-2275 10975);
DISPLAY 0.638298 (-2275 10975);
DISPLAY INVISIBLE (-2275 10975);
FORCEPROP 1 LAST PATH I191
J 0
(-2050 11075);
DISPLAY 0.978723 (-2050 11075);
PAINT WHITE (-2050 11075);
DISPLAY INVISIBLE (-2050 11075);
FORCEPROP 1 LAST PART_NUMBER CS00002JB13
J 0
(-2150 10975);
DISPLAY 0.638298 (-2150 10975);
DISPLAY INVISIBLE (-2150 10975);
FORCEADD Q_RES..1
(-2000 10875);
FORCEPROP 1 LAST LOCATION R4304
J 0
(-2150 10875);
DISPLAY 0.510638 (-2150 10875);
FORCEPROP 0 LAST $SEC 1
J 0
(-1575 10900);
DISPLAY 0.680851 (-1575 10900);
PAINT MONO (-1575 10900);
DISPLAY INVISIBLE (-1575 10900);
FORCEPROP 0 LAST CDS_SEC 1
J 0
(-1575 10900);
DISPLAY 0.680851 (-1575 10900);
DISPLAY INVISIBLE (-1575 10900);
FORCEPROP 1 LASTPIN (-2100 10875) $PN 1
J 0
(-2088 10887);
DISPLAY 0.787234 (-2088 10887);
PAINT MONO (-2088 10887);
FORCEPROP 1 LASTPIN (-1900 10875) $PN 2
J 0
(-1938 10887);
DISPLAY 0.787234 (-1938 10887);
PAINT MONO (-1938 10887);
FORCEPROP 1 LAST TOLERANCE 5%
J 0
(-1825 10875);
DISPLAY 0.510638 (-1825 10875);
FORCEPROP 1 LAST VALUE 0
J 2
(-1875 10875);
DISPLAY 0.510638 (-1875 10875);
FORCEPROP 1 LAST WATTAGE 1/16W
J 2
(-1575 10875);
DISPLAY 0.510638 (-1575 10875);
FORCEPROP 1 LAST PACK_TYPE 0402LF
J 0
(-2325 10875);
DISPLAY 0.510638 (-2325 10875);
FORCEPROP 2 LAST CDS_LIB pure_quanta
J 0
(-2000 10875);
DISPLAY INVISIBLE (-2000 10875);
FORCEPROP 1 LAST MATERIAL CHIP
J 0
(-2275 10925);
DISPLAY 0.638298 (-2275 10925);
DISPLAY INVISIBLE (-2275 10925);
FORCEPROP 1 LAST PATH I192
J 0
(-2050 11025);
DISPLAY 0.978723 (-2050 11025);
PAINT WHITE (-2050 11025);
DISPLAY INVISIBLE (-2050 11025);
FORCEPROP 1 LAST PART_NUMBER CS00002JB13
J 0
(-2150 10925);
DISPLAY 0.638298 (-2150 10925);
DISPLAY INVISIBLE (-2150 10925);
FORCEADD UNIVERSAL_GND..1
(-7125 12050);
FORCEPROP 3 LASTPIN (-7125 12100) SIG_NAME GND\g
J 0
(-7115 12110);
DISPLAY 0.659574 (-7115 12110);
PAINT MONO (-7115 12110);
DISPLAY INVISIBLE (-7115 12110);
FORCEPROP 2 LAST CDS_LIB pure_quanta_power
J 0
(-7125 12050);
DISPLAY INVISIBLE (-7125 12050);
FORCEPROP 1 LAST HDL_POWER GND
J 1
(-7100 11975);
DISPLAY 0.872340 (-7100 11975);
PAINT GREEN (-7100 11975);
DISPLAY INVISIBLE (-7100 11975);
FORCEPROP 1 LAST PATH I193
J 0
(-7050 12050);
DISPLAY 0.872340 (-7050 12050);
PAINT AQUA (-7050 12050);
DISPLAY INVISIBLE (-7050 12050);
FORCEADD Q_CAP..1
(-7125 12250);
FORCEPROP 1 LAST LOCATION C5023
J 0
(-7075 12350);
DISPLAY 0.489362 (-7075 12350);
PAINT SKYBLUE (-7075 12350);
FORCEPROP 0 LAST $SEC 1
J 0
(-7075 12375);
DISPLAY 0.680851 (-7075 12375);
PAINT MONO (-7075 12375);
DISPLAY INVISIBLE (-7075 12375);
FORCEPROP 0 LAST CDS_SEC 1
J 0
(-7075 12375);
DISPLAY 1.021277 (-7075 12375);
DISPLAY INVISIBLE (-7075 12375);
FORCEPROP 1 LASTPIN (-7125 12350) $PN 1
J 0
(-7115 12330);
DISPLAY 0.489362 (-7115 12330);
PAINT MONO (-7115 12330);
FORCEPROP 1 LASTPIN (-7125 12150) $PN 2
J 0
(-7115 12130);
DISPLAY 0.489362 (-7115 12130);
PAINT MONO (-7115 12130);
FORCEPROP 1 LAST PACK_TYPE 0402
J 0
(-7075 12050);
DISPLAY 0.489362 (-7075 12050);
PAINT SKYBLUE (-7075 12050);
FORCEPROP 1 LAST MATERIAL X7R
J 0
(-7075 12150);
DISPLAY 0.489362 (-7075 12150);
PAINT SKYBLUE (-7075 12150);
FORCEPROP 1 LAST VALUE 1000PF
J 0
(-7075 12300);
DISPLAY 0.489362 (-7075 12300);
PAINT SKYBLUE (-7075 12300);
FORCEPROP 1 LAST TOLERANCE 5%
J 0
(-7075 12200);
DISPLAY 0.489362 (-7075 12200);
PAINT SKYBLUE (-7075 12200);
FORCEPROP 1 LAST VOLTAGE 50V
J 0
(-7075 12250);
DISPLAY 0.489362 (-7075 12250);
PAINT SKYBLUE (-7075 12250);
FORCEPROP 2 LAST CDS_LIB pure_quanta
J 0
(-7125 12250);
DISPLAY INVISIBLE (-7125 12250);
FORCEPROP 1 LAST PATH I194
J 0
(-7075 12400);
DISPLAY 0.978723 (-7075 12400);
PAINT WHITE (-7075 12400);
DISPLAY INVISIBLE (-7075 12400);
FORCEPROP 1 LAST PART_NUMBER TMP_QCH21006JB10
J 0
(-7075 12100);
DISPLAY 0.489362 (-7075 12100);
PAINT SKYBLUE (-7075 12100);
DISPLAY INVISIBLE (-7075 12100);
FORCEADD Q_RES..2
R 2
(-4950 8925);
FORCEPROP 1 LAST LOCATION R5102
J 2
(-4775 8975);
DISPLAY 0.638298 (-4775 8975);
FORCEPROP 0 LAST $SEC 1
J 0
(-4775 9025);
DISPLAY 0.680851 (-4775 9025);
PAINT MONO (-4775 9025);
DISPLAY INVISIBLE (-4775 9025);
FORCEPROP 0 LAST CDS_SEC 1
J 0
(-5025 8975);
DISPLAY 0.680851 (-5025 8975);
DISPLAY INVISIBLE (-5025 8975);
FORCEPROP 1 LASTPIN (-4950 9025) $PN 1
J 2
(-4955 8987);
DISPLAY 0.787234 (-4955 8987);
PAINT MONO (-4955 8987);
FORCEPROP 1 LASTPIN (-4950 8825) $PN 2
J 2
(-4955 8835);
DISPLAY 0.787234 (-4955 8835);
PAINT MONO (-4955 8835);
FORCEPROP 1 LAST VALUE 49.9
J 2
(-4775 8875);
DISPLAY 0.638298 (-4775 8875);
FORCEPROP 2 LAST CDS_LIB pure_quanta
J 0
(-4950 8925);
DISPLAY INVISIBLE (-4950 8925);
FORCEPROP 1 LAST MATERIAL CHIP
J 2
(-4990 8850);
DISPLAY 0.978723 (-4990 8850);
DISPLAY INVISIBLE (-4990 8850);
FORCEPROP 1 LAST PACK_TYPE 0402LF
J 2
(-4990 8750);
DISPLAY 0.978723 (-4990 8750);
DISPLAY INVISIBLE (-4990 8750);
FORCEPROP 1 LAST WATTAGE 1/16W
J 2
(-4990 8900);
DISPLAY 0.978723 (-4990 8900);
DISPLAY INVISIBLE (-4990 8900);
FORCEPROP 1 LAST TOLERANCE 1%
J 2
(-4995 8950);
DISPLAY 0.978723 (-4995 8950);
DISPLAY INVISIBLE (-4995 8950);
FORCEPROP 1 LAST PATH I195
J 2
(-5000 9100);
DISPLAY 0.978723 (-5000 9100);
PAINT WHITE (-5000 9100);
DISPLAY INVISIBLE (-5000 9100);
FORCEPROP 1 LAST PART_NUMBER CS04992FB07
J 2
(-4990 8800);
DISPLAY 0.978723 (-4990 8800);
DISPLAY INVISIBLE (-4990 8800);
FORCEADD OFFPAGE..2
R 2
(-8775 7400);
FORCEPROP 2 LAST $XR1 28 
J 0
(-9089 7400);
DISPLAY 0.638298 (-9089 7400);
PAINT MONO (-9089 7400);
FORCEPROP 2 LAST $XR0 82 
J 0
(-8999 7400);
DISPLAY 0.638298 (-8999 7400);
PAINT MONO (-8999 7400);
FORCEPROP 2 LAST CDS_LIB standard
J 0
(-8775 7400);
DISPLAY INVISIBLE (-8775 7400);
FORCEPROP 1 LAST OFFPAGE TRUE
J 2
(-9100 7275);
DISPLAY 0.872340 (-9100 7275);
PAINT GREEN (-9100 7275);
DISPLAY INVISIBLE (-9100 7275);
FORCEPROP 1 LAST COMMENT_BODY TRUE
J 2
(-8730 7305);
DISPLAY 0.872340 (-8730 7305);
PAINT GREEN (-8730 7305);
DISPLAY INVISIBLE (-8730 7305);
FORCEPROP 2 LAST PATH I2
J 0
(-8725 7475);
DISPLAY 0.680851 (-8725 7475);
DISPLAY INVISIBLE (-8725 7475);
FORCEADD OFFPAGE..2
R 2
(-8750 8925);
FORCEPROP 2 LAST $XR1 81 
J 0
(-9064 8925);
DISPLAY 0.638298 (-9064 8925);
PAINT MONO (-9064 8925);
FORCEPROP 2 LAST $XR0 28 
J 0
(-8974 8925);
DISPLAY 0.638298 (-8974 8925);
PAINT MONO (-8974 8925);
FORCEPROP 2 LAST CDS_LIB standard
J 2
(-8750 8925);
DISPLAY INVISIBLE (-8750 8925);
FORCEPROP 1 LAST OFFPAGE TRUE
J 2
(-9075 8800);
DISPLAY 0.872340 (-9075 8800);
PAINT GREEN (-9075 8800);
DISPLAY INVISIBLE (-9075 8800);
FORCEPROP 1 LAST COMMENT_BODY TRUE
J 2
(-8705 8830);
DISPLAY 0.872340 (-8705 8830);
PAINT GREEN (-8705 8830);
DISPLAY INVISIBLE (-8705 8830);
FORCEPROP 2 LAST PATH I20
J 0
(-8950 8975);
DISPLAY 0.680851 (-8950 8975);
DISPLAY INVISIBLE (-8950 8975);
FORCEADD Q_RES..1
R 2
(-6850 11125);
FORCEPROP 1 LAST LOCATION R27
J 0
(-6600 11125);
DISPLAY 0.489362 (-6600 11125);
PAINT SKYBLUE (-6600 11125);
FORCEPROP 0 LAST $SEC 1
J 0
(-6550 11150);
DISPLAY 0.680851 (-6550 11150);
PAINT MONO (-6550 11150);
DISPLAY INVISIBLE (-6550 11150);
FORCEPROP 0 LAST CDS_SEC 1
J 0
(-6550 11150);
DISPLAY 1.021277 (-6550 11150);
DISPLAY INVISIBLE (-6550 11150);
FORCEPROP 1 LASTPIN (-6750 11125) $PN 1
J 2
(-6762 11137);
DISPLAY 0.489362 (-6762 11137);
PAINT MONO (-6762 11137);
FORCEPROP 1 LASTPIN (-6950 11125) $PN 2
J 2
(-6912 11137);
DISPLAY 0.489362 (-6912 11137);
PAINT MONO (-6912 11137);
FORCEPROP 1 LAST VALUE 0
J 0
(-6750 11125);
DISPLAY 0.489362 (-6750 11125);
PAINT SKYBLUE (-6750 11125);
FORCEPROP 2 LAST CDS_LIB pure_quanta
J 0
(-6850 11125);
DISPLAY INVISIBLE (-6850 11125);
FORCEPROP 1 LAST WATTAGE 1/16W
J 0
(-7250 11050);
DISPLAY 0.489362 (-7250 11050);
PAINT SKYBLUE (-7250 11050);
DISPLAY INVISIBLE (-7250 11050);
FORCEPROP 1 LAST MATERIAL CHIP
J 2
(-7275 11050);
DISPLAY 0.489362 (-7275 11050);
PAINT SKYBLUE (-7275 11050);
DISPLAY INVISIBLE (-7275 11050);
FORCEPROP 1 LAST TOLERANCE 5%
J 2
(-6825 11050);
DISPLAY 0.489362 (-6825 11050);
PAINT SKYBLUE (-6825 11050);
DISPLAY INVISIBLE (-6825 11050);
FORCEPROP 1 LAST PACK_TYPE 0402LF
J 2
(-6900 11050);
DISPLAY 0.489362 (-6900 11050);
PAINT SKYBLUE (-6900 11050);
DISPLAY INVISIBLE (-6900 11050);
FORCEPROP 1 LAST PATH I206
J 2
(-6800 11275);
DISPLAY 0.978723 (-6800 11275);
PAINT WHITE (-6800 11275);
DISPLAY INVISIBLE (-6800 11275);
FORCEPROP 1 LAST PART_NUMBER CS00002JB13
J 2
(-6875 11175);
DISPLAY 0.489362 (-6875 11175);
PAINT SKYBLUE (-6875 11175);
DISPLAY INVISIBLE (-6875 11175);
FORCEADD Q_RES..1
R 2
(-6850 11075);
FORCEPROP 1 LAST LOCATION R28
J 0
(-6600 11075);
DISPLAY 0.489362 (-6600 11075);
PAINT SKYBLUE (-6600 11075);
FORCEPROP 0 LAST $SEC 1
J 0
(-6550 11100);
DISPLAY 0.680851 (-6550 11100);
PAINT MONO (-6550 11100);
DISPLAY INVISIBLE (-6550 11100);
FORCEPROP 0 LAST CDS_SEC 1
J 0
(-6550 11100);
DISPLAY 1.021277 (-6550 11100);
DISPLAY INVISIBLE (-6550 11100);
FORCEPROP 1 LASTPIN (-6750 11075) $PN 1
J 2
(-6762 11087);
DISPLAY 0.489362 (-6762 11087);
PAINT MONO (-6762 11087);
FORCEPROP 1 LASTPIN (-6950 11075) $PN 2
J 2
(-6912 11087);
DISPLAY 0.489362 (-6912 11087);
PAINT MONO (-6912 11087);
FORCEPROP 1 LAST VALUE 0
J 0
(-6750 11075);
DISPLAY 0.489362 (-6750 11075);
PAINT SKYBLUE (-6750 11075);
FORCEPROP 2 LAST CDS_LIB pure_quanta
J 0
(-6850 11075);
DISPLAY INVISIBLE (-6850 11075);
FORCEPROP 1 LAST WATTAGE 1/16W
J 0
(-7250 11000);
DISPLAY 0.489362 (-7250 11000);
PAINT SKYBLUE (-7250 11000);
DISPLAY INVISIBLE (-7250 11000);
FORCEPROP 1 LAST MATERIAL CHIP
J 2
(-7275 11000);
DISPLAY 0.489362 (-7275 11000);
PAINT SKYBLUE (-7275 11000);
DISPLAY INVISIBLE (-7275 11000);
FORCEPROP 1 LAST TOLERANCE 5%
J 2
(-6825 11000);
DISPLAY 0.489362 (-6825 11000);
PAINT SKYBLUE (-6825 11000);
DISPLAY INVISIBLE (-6825 11000);
FORCEPROP 1 LAST PACK_TYPE 0402LF
J 2
(-6900 11000);
DISPLAY 0.489362 (-6900 11000);
PAINT SKYBLUE (-6900 11000);
DISPLAY INVISIBLE (-6900 11000);
FORCEPROP 1 LAST PATH I207
J 2
(-6800 11225);
DISPLAY 0.978723 (-6800 11225);
PAINT WHITE (-6800 11225);
DISPLAY INVISIBLE (-6800 11225);
FORCEPROP 1 LAST PART_NUMBER CS00002JB13
J 2
(-6875 11125);
DISPLAY 0.489362 (-6875 11125);
PAINT SKYBLUE (-6875 11125);
DISPLAY INVISIBLE (-6875 11125);
FORCEADD Q_RES..1
R 2
(-6850 11025);
FORCEPROP 1 LAST LOCATION R29
J 0
(-6600 11025);
DISPLAY 0.489362 (-6600 11025);
PAINT SKYBLUE (-6600 11025);
FORCEPROP 0 LAST $SEC 1
J 0
(-6550 11050);
DISPLAY 0.680851 (-6550 11050);
PAINT MONO (-6550 11050);
DISPLAY INVISIBLE (-6550 11050);
FORCEPROP 0 LAST CDS_SEC 1
J 0
(-6550 11050);
DISPLAY 1.021277 (-6550 11050);
DISPLAY INVISIBLE (-6550 11050);
FORCEPROP 1 LASTPIN (-6750 11025) $PN 1
J 2
(-6762 11037);
DISPLAY 0.489362 (-6762 11037);
PAINT MONO (-6762 11037);
FORCEPROP 1 LASTPIN (-6950 11025) $PN 2
J 2
(-6912 11037);
DISPLAY 0.489362 (-6912 11037);
PAINT MONO (-6912 11037);
FORCEPROP 1 LAST VALUE 0
J 0
(-6750 11025);
DISPLAY 0.489362 (-6750 11025);
PAINT SKYBLUE (-6750 11025);
FORCEPROP 2 LAST CDS_LIB pure_quanta
J 0
(-6850 11025);
DISPLAY INVISIBLE (-6850 11025);
FORCEPROP 1 LAST WATTAGE 1/16W
J 0
(-7250 10950);
DISPLAY 0.489362 (-7250 10950);
PAINT SKYBLUE (-7250 10950);
DISPLAY INVISIBLE (-7250 10950);
FORCEPROP 1 LAST MATERIAL CHIP
J 2
(-7275 10950);
DISPLAY 0.489362 (-7275 10950);
PAINT SKYBLUE (-7275 10950);
DISPLAY INVISIBLE (-7275 10950);
FORCEPROP 1 LAST TOLERANCE 5%
J 2
(-6825 10950);
DISPLAY 0.489362 (-6825 10950);
PAINT SKYBLUE (-6825 10950);
DISPLAY INVISIBLE (-6825 10950);
FORCEPROP 1 LAST PACK_TYPE 0402LF
J 2
(-6900 10950);
DISPLAY 0.489362 (-6900 10950);
PAINT SKYBLUE (-6900 10950);
DISPLAY INVISIBLE (-6900 10950);
FORCEPROP 1 LAST PATH I208
J 2
(-6800 11175);
DISPLAY 0.978723 (-6800 11175);
PAINT WHITE (-6800 11175);
DISPLAY INVISIBLE (-6800 11175);
FORCEPROP 1 LAST PART_NUMBER CS00002JB13
J 2
(-6875 11075);
DISPLAY 0.489362 (-6875 11075);
PAINT SKYBLUE (-6875 11075);
DISPLAY INVISIBLE (-6875 11075);
FORCEADD Q_RES..1
R 2
(-6850 10975);
FORCEPROP 1 LAST LOCATION R30
J 0
(-6600 10975);
DISPLAY 0.489362 (-6600 10975);
PAINT SKYBLUE (-6600 10975);
FORCEPROP 0 LAST $SEC 1
J 0
(-6550 11000);
DISPLAY 0.680851 (-6550 11000);
PAINT MONO (-6550 11000);
DISPLAY INVISIBLE (-6550 11000);
FORCEPROP 0 LAST CDS_SEC 1
J 0
(-6550 11000);
DISPLAY 1.021277 (-6550 11000);
DISPLAY INVISIBLE (-6550 11000);
FORCEPROP 1 LASTPIN (-6750 10975) $PN 1
J 2
(-6762 10987);
DISPLAY 0.489362 (-6762 10987);
PAINT MONO (-6762 10987);
FORCEPROP 1 LASTPIN (-6950 10975) $PN 2
J 2
(-6912 10987);
DISPLAY 0.489362 (-6912 10987);
PAINT MONO (-6912 10987);
FORCEPROP 1 LAST VALUE 0
J 0
(-6750 10975);
DISPLAY 0.489362 (-6750 10975);
PAINT SKYBLUE (-6750 10975);
FORCEPROP 2 LAST CDS_LIB pure_quanta
J 0
(-6850 10975);
DISPLAY INVISIBLE (-6850 10975);
FORCEPROP 1 LAST WATTAGE 1/16W
J 0
(-7250 10900);
DISPLAY 0.489362 (-7250 10900);
PAINT SKYBLUE (-7250 10900);
DISPLAY INVISIBLE (-7250 10900);
FORCEPROP 1 LAST MATERIAL CHIP
J 2
(-7275 10900);
DISPLAY 0.489362 (-7275 10900);
PAINT SKYBLUE (-7275 10900);
DISPLAY INVISIBLE (-7275 10900);
FORCEPROP 1 LAST TOLERANCE 5%
J 2
(-6825 10900);
DISPLAY 0.489362 (-6825 10900);
PAINT SKYBLUE (-6825 10900);
DISPLAY INVISIBLE (-6825 10900);
FORCEPROP 1 LAST PACK_TYPE 0402LF
J 2
(-6900 10900);
DISPLAY 0.489362 (-6900 10900);
PAINT SKYBLUE (-6900 10900);
DISPLAY INVISIBLE (-6900 10900);
FORCEPROP 1 LAST PATH I209
J 2
(-6800 11125);
DISPLAY 0.978723 (-6800 11125);
PAINT WHITE (-6800 11125);
DISPLAY INVISIBLE (-6800 11125);
FORCEPROP 1 LAST PART_NUMBER CS00002JB13
J 2
(-6875 11025);
DISPLAY 0.489362 (-6875 11025);
PAINT SKYBLUE (-6875 11025);
DISPLAY INVISIBLE (-6875 11025);
FORCEADD OFFPAGE..2
R 2
(-8750 8975);
FORCEPROP 2 LAST $XR1 166 
J 0
(-9094 8975);
DISPLAY 0.638298 (-9094 8975);
PAINT MONO (-9094 8975);
FORCEPROP 2 LAST $XR0 28 
J 0
(-8974 8975);
DISPLAY 0.638298 (-8974 8975);
PAINT MONO (-8974 8975);
FORCEPROP 2 LAST CDS_LIB standard
J 0
(-8750 8975);
DISPLAY INVISIBLE (-8750 8975);
FORCEPROP 1 LAST OFFPAGE TRUE
J 2
(-9075 8850);
DISPLAY 0.872340 (-9075 8850);
PAINT GREEN (-9075 8850);
DISPLAY INVISIBLE (-9075 8850);
FORCEPROP 1 LAST COMMENT_BODY TRUE
J 2
(-8705 8880);
DISPLAY 0.872340 (-8705 8880);
PAINT GREEN (-8705 8880);
DISPLAY INVISIBLE (-8705 8880);
FORCEPROP 2 LAST PATH I21
J 0
(-8950 9025);
DISPLAY 0.680851 (-8950 9025);
DISPLAY INVISIBLE (-8950 9025);
FORCEADD Q_RES..1
(-8275 11125);
FORCEPROP 1 LAST LOCATION R6081
J 0
(-8450 11125);
DISPLAY 0.489362 (-8450 11125);
PAINT SKYBLUE (-8450 11125);
FORCEPROP 0 LAST $SEC 1
J 0
(-8375 11200);
DISPLAY 0.680851 (-8375 11200);
PAINT MONO (-8375 11200);
DISPLAY INVISIBLE (-8375 11200);
FORCEPROP 0 LAST CDS_SEC 1
J 0
(-8375 11200);
DISPLAY 1.021277 (-8375 11200);
DISPLAY INVISIBLE (-8375 11200);
FORCEPROP 1 LASTPIN (-8375 11125) $PN 1
J 0
(-8363 11137);
DISPLAY 0.489362 (-8363 11137);
PAINT MONO (-8363 11137);
FORCEPROP 1 LASTPIN (-8175 11125) $PN 2
J 0
(-8213 11137);
DISPLAY 0.489362 (-8213 11137);
PAINT MONO (-8213 11137);
FORCEPROP 1 LAST VALUE 4.7K
J 0
(-8150 11125);
DISPLAY 0.489362 (-8150 11125);
PAINT SKYBLUE (-8150 11125);
FORCEPROP 2 LAST CDS_LIB pure_quanta
J 0
(-8275 11125);
DISPLAY INVISIBLE (-8275 11125);
FORCEPROP 1 LAST WATTAGE 1/16W
J 2
(-8300 10975);
DISPLAY 0.510638 (-8300 10975);
PAINT SKYBLUE (-8300 10975);
DISPLAY INVISIBLE (-8300 10975);
FORCEPROP 1 LAST MATERIAL CHIP
J 0
(-8175 11100);
DISPLAY 0.489362 (-8175 11100);
PAINT SKYBLUE (-8175 11100);
DISPLAY INVISIBLE (-8175 11100);
FORCEPROP 1 LAST TOLERANCE 5%
J 0
(-8150 11125);
DISPLAY 0.510638 (-8150 11125);
PAINT SKYBLUE (-8150 11125);
DISPLAY INVISIBLE (-8150 11125);
FORCEPROP 1 LAST PACK_TYPE 0402LF
J 0
(-8025 10975);
DISPLAY 0.510638 (-8025 10975);
PAINT SKYBLUE (-8025 10975);
DISPLAY INVISIBLE (-8025 10975);
FORCEPROP 1 LAST PATH I210
J 0
(-8325 11275);
DISPLAY 0.978723 (-8325 11275);
PAINT WHITE (-8325 11275);
DISPLAY INVISIBLE (-8325 11275);
FORCEPROP 1 LAST PART_NUMBER CS24702JB10
J 0
(-8325 11225);
DISPLAY 0.510638 (-8325 11225);
PAINT SKYBLUE (-8325 11225);
DISPLAY INVISIBLE (-8325 11225);
FORCEADD VCC_CORE..1
(-8475 11375);
FORCEPROP 3 LASTPIN (-8475 11325) SIG_NAME PVDD11_S3_P0\g
J 0
(-8465 11335);
DISPLAY 0.659574 (-8465 11335);
PAINT MONO (-8465 11335);
DISPLAY INVISIBLE (-8465 11335);
FORCEPROP 1 LAST HDL_POWER PVDD11_S3_P0
J 1
(-8475 11425);
DISPLAY 0.489362 (-8475 11425);
PAINT GREEN (-8475 11425);
FORCEPROP 2 LAST CDS_LIB pure_quanta_power
J 0
(-8475 11375);
DISPLAY INVISIBLE (-8475 11375);
FORCEPROP 1 LAST PATH I211
J 0
(-8425 11400);
DISPLAY 0.872340 (-8425 11400);
PAINT AQUA (-8425 11400);
DISPLAY INVISIBLE (-8425 11400);
FORCEADD Q_RES..1
(-8275 11075);
FORCEPROP 1 LAST LOCATION R6082
J 0
(-8450 11075);
DISPLAY 0.489362 (-8450 11075);
PAINT SKYBLUE (-8450 11075);
FORCEPROP 0 LAST $SEC 1
J 0
(-8375 11150);
DISPLAY 0.680851 (-8375 11150);
PAINT MONO (-8375 11150);
DISPLAY INVISIBLE (-8375 11150);
FORCEPROP 0 LAST CDS_SEC 1
J 0
(-8375 11150);
DISPLAY 1.021277 (-8375 11150);
DISPLAY INVISIBLE (-8375 11150);
FORCEPROP 1 LASTPIN (-8375 11075) $PN 1
J 0
(-8363 11087);
DISPLAY 0.489362 (-8363 11087);
PAINT MONO (-8363 11087);
FORCEPROP 1 LASTPIN (-8175 11075) $PN 2
J 0
(-8213 11087);
DISPLAY 0.489362 (-8213 11087);
PAINT MONO (-8213 11087);
FORCEPROP 1 LAST VALUE 4.7K
J 0
(-8150 11075);
DISPLAY 0.489362 (-8150 11075);
PAINT SKYBLUE (-8150 11075);
FORCEPROP 2 LAST CDS_LIB pure_quanta
J 0
(-8275 11075);
DISPLAY INVISIBLE (-8275 11075);
FORCEPROP 1 LAST WATTAGE 1/16W
J 2
(-8300 10925);
DISPLAY 0.510638 (-8300 10925);
PAINT SKYBLUE (-8300 10925);
DISPLAY INVISIBLE (-8300 10925);
FORCEPROP 1 LAST MATERIAL CHIP
J 0
(-8175 11050);
DISPLAY 0.489362 (-8175 11050);
PAINT SKYBLUE (-8175 11050);
DISPLAY INVISIBLE (-8175 11050);
FORCEPROP 1 LAST TOLERANCE 5%
J 0
(-8150 11075);
DISPLAY 0.510638 (-8150 11075);
PAINT SKYBLUE (-8150 11075);
DISPLAY INVISIBLE (-8150 11075);
FORCEPROP 1 LAST PACK_TYPE 0402LF
J 0
(-8025 10925);
DISPLAY 0.510638 (-8025 10925);
PAINT SKYBLUE (-8025 10925);
DISPLAY INVISIBLE (-8025 10925);
FORCEPROP 1 LAST PATH I212
J 0
(-8325 11225);
DISPLAY 0.978723 (-8325 11225);
PAINT WHITE (-8325 11225);
DISPLAY INVISIBLE (-8325 11225);
FORCEPROP 1 LAST PART_NUMBER CS24702JB10
J 0
(-8325 11175);
DISPLAY 0.510638 (-8325 11175);
PAINT SKYBLUE (-8325 11175);
DISPLAY INVISIBLE (-8325 11175);
FORCEADD Q_RES..1
(-8275 11025);
FORCEPROP 1 LAST LOCATION R6083
J 0
(-8450 11025);
DISPLAY 0.489362 (-8450 11025);
PAINT SKYBLUE (-8450 11025);
FORCEPROP 0 LAST $SEC 1
J 0
(-8375 11100);
DISPLAY 0.680851 (-8375 11100);
PAINT MONO (-8375 11100);
DISPLAY INVISIBLE (-8375 11100);
FORCEPROP 0 LAST CDS_SEC 1
J 0
(-8375 11100);
DISPLAY 1.021277 (-8375 11100);
DISPLAY INVISIBLE (-8375 11100);
FORCEPROP 1 LASTPIN (-8375 11025) $PN 1
J 0
(-8363 11037);
DISPLAY 0.489362 (-8363 11037);
PAINT MONO (-8363 11037);
FORCEPROP 1 LASTPIN (-8175 11025) $PN 2
J 0
(-8213 11037);
DISPLAY 0.489362 (-8213 11037);
PAINT MONO (-8213 11037);
FORCEPROP 1 LAST VALUE 4.7K
J 0
(-8150 11025);
DISPLAY 0.489362 (-8150 11025);
PAINT SKYBLUE (-8150 11025);
FORCEPROP 2 LAST CDS_LIB pure_quanta
J 0
(-8275 11025);
DISPLAY INVISIBLE (-8275 11025);
FORCEPROP 1 LAST WATTAGE 1/16W
J 2
(-8300 10875);
DISPLAY 0.510638 (-8300 10875);
PAINT SKYBLUE (-8300 10875);
DISPLAY INVISIBLE (-8300 10875);
FORCEPROP 1 LAST MATERIAL CHIP
J 0
(-8175 11000);
DISPLAY 0.489362 (-8175 11000);
PAINT SKYBLUE (-8175 11000);
DISPLAY INVISIBLE (-8175 11000);
FORCEPROP 1 LAST TOLERANCE 5%
J 0
(-8150 11025);
DISPLAY 0.510638 (-8150 11025);
PAINT SKYBLUE (-8150 11025);
DISPLAY INVISIBLE (-8150 11025);
FORCEPROP 1 LAST PACK_TYPE 0402LF
J 0
(-8025 10875);
DISPLAY 0.510638 (-8025 10875);
PAINT SKYBLUE (-8025 10875);
DISPLAY INVISIBLE (-8025 10875);
FORCEPROP 1 LAST PATH I213
J 0
(-8325 11175);
DISPLAY 0.978723 (-8325 11175);
PAINT WHITE (-8325 11175);
DISPLAY INVISIBLE (-8325 11175);
FORCEPROP 1 LAST PART_NUMBER CS24702JB10
J 0
(-8325 11125);
DISPLAY 0.510638 (-8325 11125);
PAINT SKYBLUE (-8325 11125);
DISPLAY INVISIBLE (-8325 11125);
FORCEADD Q_RES..1
(-8275 10975);
FORCEPROP 1 LAST LOCATION R6084
J 0
(-8450 10975);
DISPLAY 0.489362 (-8450 10975);
PAINT SKYBLUE (-8450 10975);
FORCEPROP 0 LAST $SEC 1
J 0
(-8375 11050);
DISPLAY 0.680851 (-8375 11050);
PAINT MONO (-8375 11050);
DISPLAY INVISIBLE (-8375 11050);
FORCEPROP 0 LAST CDS_SEC 1
J 0
(-8375 11050);
DISPLAY 1.021277 (-8375 11050);
DISPLAY INVISIBLE (-8375 11050);
FORCEPROP 1 LASTPIN (-8375 10975) $PN 1
J 0
(-8363 10987);
DISPLAY 0.489362 (-8363 10987);
PAINT MONO (-8363 10987);
FORCEPROP 1 LASTPIN (-8175 10975) $PN 2
J 0
(-8213 10987);
DISPLAY 0.489362 (-8213 10987);
PAINT MONO (-8213 10987);
FORCEPROP 1 LAST VALUE 4.7K
J 0
(-8150 10975);
DISPLAY 0.489362 (-8150 10975);
PAINT SKYBLUE (-8150 10975);
FORCEPROP 2 LAST CDS_LIB pure_quanta
J 0
(-8275 10975);
DISPLAY INVISIBLE (-8275 10975);
FORCEPROP 1 LAST WATTAGE 1/16W
J 2
(-8300 10825);
DISPLAY 0.510638 (-8300 10825);
PAINT SKYBLUE (-8300 10825);
DISPLAY INVISIBLE (-8300 10825);
FORCEPROP 1 LAST MATERIAL CHIP
J 0
(-8175 10950);
DISPLAY 0.489362 (-8175 10950);
PAINT SKYBLUE (-8175 10950);
DISPLAY INVISIBLE (-8175 10950);
FORCEPROP 1 LAST TOLERANCE 5%
J 0
(-8150 10975);
DISPLAY 0.510638 (-8150 10975);
PAINT SKYBLUE (-8150 10975);
DISPLAY INVISIBLE (-8150 10975);
FORCEPROP 1 LAST PACK_TYPE 0402LF
J 0
(-8025 10825);
DISPLAY 0.510638 (-8025 10825);
PAINT SKYBLUE (-8025 10825);
DISPLAY INVISIBLE (-8025 10825);
FORCEPROP 1 LAST PATH I214
J 0
(-8325 11125);
DISPLAY 0.978723 (-8325 11125);
PAINT WHITE (-8325 11125);
DISPLAY INVISIBLE (-8325 11125);
FORCEPROP 1 LAST PART_NUMBER CS24702JB10
J 0
(-8325 11075);
DISPLAY 0.510638 (-8325 11075);
PAINT SKYBLUE (-8325 11075);
DISPLAY INVISIBLE (-8325 11075);
FORCEADD OFFPAGE..4
R 2
(-7300 9625);
FORCEPROP 2 LAST $XR0 84 
J 0
(-7521 9625);
DISPLAY 0.638298 (-7521 9625);
PAINT MONO (-7521 9625);
FORCEPROP 2 LAST CDS_LIB standard
J 0
(-7300 9625);
DISPLAY INVISIBLE (-7300 9625);
FORCEPROP 1 LAST OFFPAGE TRUE
J 2
(-7625 9500);
DISPLAY 0.872340 (-7625 9500);
PAINT GREEN (-7625 9500);
DISPLAY INVISIBLE (-7625 9500);
FORCEPROP 1 LAST COMMENT_BODY TRUE
J 2
(-7275 9525);
DISPLAY 0.872340 (-7275 9525);
PAINT GREEN (-7275 9525);
DISPLAY INVISIBLE (-7275 9525);
FORCEPROP 2 LAST PATH I215
J 0
(-7500 9675);
DISPLAY 0.680851 (-7500 9675);
DISPLAY INVISIBLE (-7500 9675);
FORCEADD OFFPAGE..4
R 2
(-7300 9725);
FORCEPROP 2 LAST $XR0 84 
J 0
(-7521 9725);
DISPLAY 0.638298 (-7521 9725);
PAINT MONO (-7521 9725);
FORCEPROP 2 LAST CDS_LIB standard
J 0
(-7300 9725);
DISPLAY INVISIBLE (-7300 9725);
FORCEPROP 1 LAST OFFPAGE TRUE
J 2
(-7625 9600);
DISPLAY 0.872340 (-7625 9600);
PAINT GREEN (-7625 9600);
DISPLAY INVISIBLE (-7625 9600);
FORCEPROP 1 LAST COMMENT_BODY TRUE
J 2
(-7275 9625);
DISPLAY 0.872340 (-7275 9625);
PAINT GREEN (-7275 9625);
DISPLAY INVISIBLE (-7275 9625);
FORCEPROP 2 LAST PATH I216
J 0
(-7500 9775);
DISPLAY 0.680851 (-7500 9775);
DISPLAY INVISIBLE (-7500 9775);
FORCEADD OFFPAGE..4
R 2
(-7300 9775);
FORCEPROP 2 LAST $XR0 84 
J 0
(-7521 9775);
DISPLAY 0.638298 (-7521 9775);
PAINT MONO (-7521 9775);
FORCEPROP 2 LAST CDS_LIB standard
J 0
(-7300 9775);
DISPLAY INVISIBLE (-7300 9775);
FORCEPROP 1 LAST OFFPAGE TRUE
J 2
(-7625 9650);
DISPLAY 0.872340 (-7625 9650);
PAINT GREEN (-7625 9650);
DISPLAY INVISIBLE (-7625 9650);
FORCEPROP 1 LAST COMMENT_BODY TRUE
J 2
(-7275 9675);
DISPLAY 0.872340 (-7275 9675);
PAINT GREEN (-7275 9675);
DISPLAY INVISIBLE (-7275 9675);
FORCEPROP 2 LAST PATH I217
J 0
(-7500 9825);
DISPLAY 0.680851 (-7500 9825);
DISPLAY INVISIBLE (-7500 9825);
FORCEADD OFFPAGE..4
R 2
(-7300 10075);
FORCEPROP 2 LAST $XR0 84 
J 0
(-7521 10075);
DISPLAY 0.638298 (-7521 10075);
PAINT MONO (-7521 10075);
FORCEPROP 2 LAST CDS_LIB standard
J 0
(-7300 10075);
DISPLAY INVISIBLE (-7300 10075);
FORCEPROP 1 LAST OFFPAGE TRUE
J 2
(-7625 9950);
DISPLAY 0.872340 (-7625 9950);
PAINT GREEN (-7625 9950);
DISPLAY INVISIBLE (-7625 9950);
FORCEPROP 1 LAST COMMENT_BODY TRUE
J 2
(-7275 9975);
DISPLAY 0.872340 (-7275 9975);
PAINT GREEN (-7275 9975);
DISPLAY INVISIBLE (-7275 9975);
FORCEPROP 2 LAST PATH I218
J 0
(-7500 10125);
DISPLAY 0.680851 (-7500 10125);
DISPLAY INVISIBLE (-7500 10125);
FORCEADD OFFPAGE..4
R 2
(-7300 10025);
FORCEPROP 2 LAST $XR0 84 
J 0
(-7521 10025);
DISPLAY 0.638298 (-7521 10025);
PAINT MONO (-7521 10025);
FORCEPROP 2 LAST CDS_LIB standard
J 0
(-7300 10025);
DISPLAY INVISIBLE (-7300 10025);
FORCEPROP 1 LAST OFFPAGE TRUE
J 2
(-7625 9900);
DISPLAY 0.872340 (-7625 9900);
PAINT GREEN (-7625 9900);
DISPLAY INVISIBLE (-7625 9900);
FORCEPROP 1 LAST COMMENT_BODY TRUE
J 2
(-7275 9925);
DISPLAY 0.872340 (-7275 9925);
PAINT GREEN (-7275 9925);
DISPLAY INVISIBLE (-7275 9925);
FORCEPROP 2 LAST PATH I219
J 0
(-7500 10075);
DISPLAY 0.680851 (-7500 10075);
DISPLAY INVISIBLE (-7500 10075);
FORCEADD Q_RES..2
(-9100 9650);
FORCEPROP 1 LAST LOCATION R420
J 0
(-9050 9725);
DISPLAY 0.489362 (-9050 9725);
PAINT SKYBLUE (-9050 9725);
FORCEPROP 0 LAST $SEC 1
J 2
(-9050 9775);
DISPLAY 0.680851 (-9050 9775);
PAINT MONO (-9050 9775);
DISPLAY INVISIBLE (-9050 9775);
FORCEPROP 0 LAST CDS_SEC 1
J 2
(-9050 9775);
DISPLAY 1.021277 (-9050 9775);
DISPLAY INVISIBLE (-9050 9775);
FORCEPROP 1 LASTPIN (-9100 9750) $PN 1
J 0
(-9095 9712);
DISPLAY 0.489362 (-9095 9712);
PAINT MONO (-9095 9712);
FORCEPROP 1 LASTPIN (-9100 9550) $PN 2
J 0
(-9095 9560);
DISPLAY 0.489362 (-9095 9560);
PAINT MONO (-9095 9560);
FORCEPROP 1 LAST TOLERANCE 1%
J 0
(-9050 9675);
DISPLAY 0.489362 (-9050 9675);
PAINT SKYBLUE (-9050 9675);
FORCEPROP 1 LAST VALUE 1K
J 0
(-9050 9700);
DISPLAY 0.489362 (-9050 9700);
PAINT SKYBLUE (-9050 9700);
FORCEPROP 1 LAST MATERIAL EMPTY
J 0
(-9050 9625);
DISPLAY 0.489362 (-9050 9625);
PAINT RED (-9050 9625);
FORCEPROP 2 LAST CDS_LIB pure_quanta
J 2
(-9100 9650);
DISPLAY INVISIBLE (-9100 9650);
FORCEPROP 1 LAST WATTAGE 1/16W
J 0
(-9050 9650);
DISPLAY 0.489362 (-9050 9650);
PAINT SKYBLUE (-9050 9650);
DISPLAY INVISIBLE (-9050 9650);
FORCEPROP 1 LAST PACK_TYPE 0402LF
J 0
(-9050 9600);
DISPLAY 0.489362 (-9050 9600);
PAINT SKYBLUE (-9050 9600);
DISPLAY INVISIBLE (-9050 9600);
FORCEPROP 1 LAST PATH I22
J 0
(-9050 9825);
DISPLAY 0.978723 (-9050 9825);
PAINT WHITE (-9050 9825);
DISPLAY INVISIBLE (-9050 9825);
FORCEPROP 1 LAST PART_NUMBER CS21002FB06
J 0
(-9050 9575);
DISPLAY 0.489362 (-9050 9575);
PAINT SKYBLUE (-9050 9575);
DISPLAY INVISIBLE (-9050 9575);
FORCEADD OFFPAGE..3
(-2125 10075);
FORCEPROP 2 LAST $XR0 161 
J 0
(-1911 10075);
DISPLAY 0.638298 (-1911 10075);
PAINT MONO (-1911 10075);
FORCEPROP 2 LAST CDS_LIB standard
J 0
(-2125 10075);
DISPLAY INVISIBLE (-2125 10075);
FORCEPROP 1 LAST OFFPAGE TRUE
J 0
(-1800 9950);
DISPLAY 0.872340 (-1800 9950);
PAINT GREEN (-1800 9950);
DISPLAY INVISIBLE (-1800 9950);
FORCEPROP 1 LAST COMMENT_BODY TRUE
J 0
(-2175 9975);
DISPLAY 0.872340 (-2175 9975);
PAINT PEACH (-2175 9975);
DISPLAY INVISIBLE (-2175 9975);
FORCEPROP 2 LAST PATH I220
J 0
(-1925 10150);
DISPLAY 0.680851 (-1925 10150);
DISPLAY INVISIBLE (-1925 10150);
FORCEADD Q_RES..1
(-3350 8450);
FORCEPROP 1 LAST LOCATION R433
J 0
(-3400 8500);
DISPLAY 0.638298 (-3400 8500);
FORCEPROP 2 LAST SEC 1
J 0
(-3400 8650);
DISPLAY 0.680851 (-3400 8650);
PAINT MONO (-3400 8650);
DISPLAY INVISIBLE (-3400 8650);
FORCEPROP 1 LASTPIN (-3450 8450) $PN 1
J 0
(-3438 8462);
DISPLAY 0.638298 (-3438 8462);
PAINT MONO (-3438 8462);
FORCEPROP 1 LASTPIN (-3250 8450) $PN 2
J 0
(-3288 8462);
DISPLAY 0.638298 (-3288 8462);
PAINT MONO (-3288 8462);
FORCEPROP 1 LAST PACK_TYPE 0402LF
J 0
(-3100 8300);
DISPLAY 0.638298 (-3100 8300);
FORCEPROP 1 LAST VALUE 20M
J 2
(-3375 8350);
DISPLAY 0.638298 (-3375 8350);
FORCEPROP 1 LAST WATTAGE 1/16W
J 2
(-3375 8300);
DISPLAY 0.638298 (-3375 8300);
FORCEPROP 1 LAST TOLERANCE 1%
J 0
(-3350 8350);
DISPLAY 0.638298 (-3350 8350);
FORCEPROP 1 LAST MATERIAL CHIP
J 0
(-3350 8300);
DISPLAY 0.638298 (-3350 8300);
FORCEPROP 2 LAST SEC_TYPE 0402LF
J 0
(-3400 8650);
DISPLAY 0.680851 (-3400 8650);
DISPLAY INVISIBLE (-3400 8650);
FORCEPROP 2 LAST CDS_LIB pure_quanta
J 0
(-3350 8450);
DISPLAY INVISIBLE (-3350 8450);
FORCEPROP 1 LAST PATH I221
J 0
(-3400 8600);
DISPLAY 0.978723 (-3400 8600);
PAINT WHITE (-3400 8600);
DISPLAY INVISIBLE (-3400 8600);
FORCEPROP 1 LAST PART_NUMBER CS62002FB01
J 0
(-3400 8550);
DISPLAY 0.638298 (-3400 8550);
DISPLAY INVISIBLE (-3400 8550);
FORCEADD Q_RES..1
(-7775 8925);
FORCEPROP 1 LAST LOCATION R438
J 0
(-7975 8925);
DISPLAY 0.510638 (-7975 8925);
FORCEPROP 2 LAST SEC 1
J 0
(-7825 9125);
DISPLAY 0.680851 (-7825 9125);
PAINT MONO (-7825 9125);
DISPLAY INVISIBLE (-7825 9125);
FORCEPROP 1 LASTPIN (-7875 8925) $PN 1
J 0
(-7863 8937);
DISPLAY 0.510638 (-7863 8937);
PAINT MONO (-7863 8937);
FORCEPROP 1 LASTPIN (-7675 8925) $PN 2
J 0
(-7713 8937);
DISPLAY 0.510638 (-7713 8937);
PAINT MONO (-7713 8937);
FORCEPROP 1 LAST VALUE 4.7K
J 2
(-7575 8925);
DISPLAY 0.510638 (-7575 8925);
FORCEPROP 1 LAST MATERIAL EMPTY
J 0
(-8125 8925);
DISPLAY 0.510638 (-8125 8925);
PAINT RED (-8125 8925);
FORCEPROP 1 LAST TOLERANCE 5%
J 0
(-7775 8825);
DISPLAY 0.638298 (-7775 8825);
DISPLAY INVISIBLE (-7775 8825);
FORCEPROP 1 LAST WATTAGE 1/16W
J 2
(-7800 8775);
DISPLAY 0.638298 (-7800 8775);
DISPLAY INVISIBLE (-7800 8775);
FORCEPROP 1 LAST PACK_TYPE 0402LF
J 0
(-7525 8775);
DISPLAY 0.638298 (-7525 8775);
DISPLAY INVISIBLE (-7525 8775);
FORCEPROP 2 LAST SEC_TYPE 0402LF
J 0
(-7825 9125);
DISPLAY 0.680851 (-7825 9125);
DISPLAY INVISIBLE (-7825 9125);
FORCEPROP 2 LAST CDS_LIB pure_quanta
J 0
(-7775 8925);
DISPLAY INVISIBLE (-7775 8925);
FORCEPROP 1 LAST PATH I222
J 0
(-7825 9075);
DISPLAY 0.978723 (-7825 9075);
PAINT WHITE (-7825 9075);
DISPLAY INVISIBLE (-7825 9075);
FORCEPROP 1 LAST PART_NUMBER CS24702JB10
J 0
(-7825 9025);
DISPLAY 0.638298 (-7825 9025);
DISPLAY INVISIBLE (-7825 9025);
FORCEADD OFFPAGE..2
R 2
(-7025 8900);
FORCEPROP 2 LAST $XR1 81 
J 0
(-7369 8900);
DISPLAY 0.638298 (-7369 8900);
PAINT MONO (-7369 8900);
FORCEPROP 2 LAST $XR0 28 
J 0
(-7279 8900);
DISPLAY 0.638298 (-7279 8900);
PAINT MONO (-7279 8900);
FORCEPROP 2 LAST CDS_LIB standard
J 0
(-7025 8900);
DISPLAY INVISIBLE (-7025 8900);
FORCEPROP 1 LAST OFFPAGE TRUE
J 2
(-7350 8775);
DISPLAY 0.872340 (-7350 8775);
PAINT GREEN (-7350 8775);
DISPLAY INVISIBLE (-7350 8775);
FORCEPROP 1 LAST COMMENT_BODY TRUE
J 2
(-6980 8805);
DISPLAY 0.872340 (-6980 8805);
PAINT GREEN (-6980 8805);
DISPLAY INVISIBLE (-6980 8805);
FORCEPROP 2 LAST PATH I223
J 0
(-6975 8975);
DISPLAY 0.680851 (-6975 8975);
DISPLAY INVISIBLE (-6975 8975);
FORCEADD Q_RES..2
R 2
(-6350 8675);
FORCEPROP 1 LAST LOCATION R6502
J 2
(-6395 8800);
DISPLAY 0.808511 (-6395 8800);
FORCEPROP 0 LAST $SEC 1
J 0
(-6375 8850);
DISPLAY 0.680851 (-6375 8850);
PAINT MONO (-6375 8850);
DISPLAY INVISIBLE (-6375 8850);
FORCEPROP 0 LAST CDS_SEC 1
J 0
(-6375 8850);
DISPLAY 0.680851 (-6375 8850);
DISPLAY INVISIBLE (-6375 8850);
FORCEPROP 1 LASTPIN (-6350 8775) $PN 1
J 2
(-6355 8737);
DISPLAY 0.787234 (-6355 8737);
PAINT MONO (-6355 8737);
FORCEPROP 1 LASTPIN (-6350 8575) $PN 2
J 2
(-6355 8585);
DISPLAY 0.787234 (-6355 8585);
PAINT MONO (-6355 8585);
FORCEPROP 1 LAST MATERIAL CHIP
J 2
(-6390 8600);
DISPLAY 0.638298 (-6390 8600);
FORCEPROP 1 LAST VALUE 2.2K
J 2
(-6395 8750);
DISPLAY 0.638298 (-6395 8750);
FORCEPROP 1 LAST TOLERANCE 5%
J 2
(-6395 8700);
DISPLAY 0.638298 (-6395 8700);
FORCEPROP 1 LAST WATTAGE 1/16W
J 2
(-6390 8650);
DISPLAY 0.638298 (-6390 8650);
FORCEPROP 1 LAST PACK_TYPE 0402LF
J 2
(-6390 8500);
DISPLAY 0.638298 (-6390 8500);
FORCEPROP 2 LAST CDS_LIB pure_quanta
J 2
(-6350 8675);
DISPLAY INVISIBLE (-6350 8675);
FORCEPROP 1 LAST PATH I224
J 2
(-6400 8850);
DISPLAY 0.978723 (-6400 8850);
PAINT WHITE (-6400 8850);
DISPLAY INVISIBLE (-6400 8850);
FORCEPROP 1 LAST PART_NUMBER CS22202JB07
J 2
(-6390 8550);
DISPLAY 0.638298 (-6390 8550);
DISPLAY INVISIBLE (-6390 8550);
FORCEADD UNIVERSAL_GND..1
(-6350 8225);
FORCEPROP 3 LASTPIN (-6350 8275) SIG_NAME GND\g
J 0
(-6340 8285);
DISPLAY 0.659574 (-6340 8285);
PAINT MONO (-6340 8285);
DISPLAY INVISIBLE (-6340 8285);
FORCEPROP 2 LAST CDS_LIB pure_quanta_power
J 0
(-6350 8225);
DISPLAY INVISIBLE (-6350 8225);
FORCEPROP 1 LAST HDL_POWER GND
J 1
(-6325 8150);
DISPLAY 0.872340 (-6325 8150);
PAINT GREEN (-6325 8150);
DISPLAY INVISIBLE (-6325 8150);
FORCEPROP 1 LAST PATH I225
J 0
(-6275 8225);
DISPLAY 0.872340 (-6275 8225);
PAINT AQUA (-6275 8225);
DISPLAY INVISIBLE (-6275 8225);
FORCEADD OFFPAGE..2
(-600 10775);
FORCEPROP 2 LAST $XR0 182 
J 0
(-411 10775);
DISPLAY 0.638298 (-411 10775);
PAINT MONO (-411 10775);
FORCEPROP 2 LAST CDS_LIB standard
J 0
(-600 10775);
DISPLAY INVISIBLE (-600 10775);
FORCEPROP 1 LAST OFFPAGE TRUE
J 0
(-275 10650);
DISPLAY 0.872340 (-275 10650);
PAINT GREEN (-275 10650);
DISPLAY INVISIBLE (-275 10650);
FORCEPROP 1 LAST COMMENT_BODY TRUE
J 0
(-645 10680);
DISPLAY 0.872340 (-645 10680);
PAINT GREEN (-645 10680);
DISPLAY INVISIBLE (-645 10680);
FORCEPROP 2 LAST PATH I226
J 0
(-425 10850);
DISPLAY 0.680851 (-425 10850);
DISPLAY INVISIBLE (-425 10850);
FORCEADD OFFPAGE..2
(-600 10725);
FORCEPROP 2 LAST $XR0 182 
J 0
(-411 10725);
DISPLAY 0.638298 (-411 10725);
PAINT MONO (-411 10725);
FORCEPROP 2 LAST CDS_LIB standard
J 0
(-600 10725);
DISPLAY INVISIBLE (-600 10725);
FORCEPROP 1 LAST OFFPAGE TRUE
J 0
(-275 10600);
DISPLAY 0.872340 (-275 10600);
PAINT GREEN (-275 10600);
DISPLAY INVISIBLE (-275 10600);
FORCEPROP 1 LAST COMMENT_BODY TRUE
J 0
(-645 10630);
DISPLAY 0.872340 (-645 10630);
PAINT GREEN (-645 10630);
DISPLAY INVISIBLE (-645 10630);
FORCEPROP 2 LAST PATH I227
J 0
(-425 10800);
DISPLAY 0.680851 (-425 10800);
DISPLAY INVISIBLE (-425 10800);
FORCEADD Q_RES..1
(-2000 10725);
FORCEPROP 1 LAST LOCATION R8306
J 0
(-2175 10725);
DISPLAY 0.510638 (-2175 10725);
FORCEPROP 2 LAST SEC 1
J 0
(-2050 10925);
DISPLAY 0.680851 (-2050 10925);
PAINT MONO (-2050 10925);
DISPLAY INVISIBLE (-2050 10925);
FORCEPROP 1 LASTPIN (-2100 10725) $PN 1
J 0
(-2088 10737);
DISPLAY 0.638298 (-2088 10737);
PAINT MONO (-2088 10737);
FORCEPROP 1 LASTPIN (-1900 10725) $PN 2
J 0
(-1938 10737);
DISPLAY 0.638298 (-1938 10737);
PAINT MONO (-1938 10737);
FORCEPROP 1 LAST TOLERANCE 5%
J 0
(-1825 10725);
DISPLAY 0.510638 (-1825 10725);
FORCEPROP 1 LAST WATTAGE 1/16W
J 2
(-1575 10725);
DISPLAY 0.510638 (-1575 10725);
FORCEPROP 1 LAST VALUE 0
J 2
(-1875 10725);
DISPLAY 0.510638 (-1875 10725);
FORCEPROP 1 LAST PACK_TYPE 0402LF
J 0
(-2325 10725);
DISPLAY 0.510638 (-2325 10725);
FORCEPROP 2 LAST SEC_TYPE 0402LF
J 0
(-2050 10925);
DISPLAY 0.680851 (-2050 10925);
DISPLAY INVISIBLE (-2050 10925);
FORCEPROP 1 LAST MATERIAL CHIP
J 0
(-2275 10775);
DISPLAY 0.638298 (-2275 10775);
DISPLAY INVISIBLE (-2275 10775);
FORCEPROP 2 LAST CDS_LIB pure_quanta
J 0
(-2000 10725);
DISPLAY INVISIBLE (-2000 10725);
FORCEPROP 1 LAST PATH I228
J 0
(-2050 10875);
DISPLAY 0.978723 (-2050 10875);
PAINT WHITE (-2050 10875);
DISPLAY INVISIBLE (-2050 10875);
FORCEPROP 1 LAST PART_NUMBER CS00002JB13
J 0
(-2150 10775);
DISPLAY 0.638298 (-2150 10775);
DISPLAY INVISIBLE (-2150 10775);
FORCEADD Q_RES..1
(-2000 10775);
FORCEPROP 1 LAST LOCATION R8305
J 0
(-2175 10775);
DISPLAY 0.510638 (-2175 10775);
FORCEPROP 2 LAST SEC 1
J 0
(-2050 10975);
DISPLAY 0.680851 (-2050 10975);
PAINT MONO (-2050 10975);
DISPLAY INVISIBLE (-2050 10975);
FORCEPROP 1 LASTPIN (-2100 10775) $PN 1
J 0
(-2088 10787);
DISPLAY 0.638298 (-2088 10787);
PAINT MONO (-2088 10787);
FORCEPROP 1 LASTPIN (-1900 10775) $PN 2
J 0
(-1938 10787);
DISPLAY 0.638298 (-1938 10787);
PAINT MONO (-1938 10787);
FORCEPROP 1 LAST VALUE 0
J 2
(-1875 10775);
DISPLAY 0.510638 (-1875 10775);
FORCEPROP 1 LAST TOLERANCE 5%
J 0
(-1825 10775);
DISPLAY 0.510638 (-1825 10775);
FORCEPROP 1 LAST PACK_TYPE 0402LF
J 0
(-2325 10775);
DISPLAY 0.510638 (-2325 10775);
FORCEPROP 1 LAST WATTAGE 1/16W
J 2
(-1575 10775);
DISPLAY 0.510638 (-1575 10775);
FORCEPROP 2 LAST SEC_TYPE 0402LF
J 0
(-2050 10975);
DISPLAY 0.680851 (-2050 10975);
DISPLAY INVISIBLE (-2050 10975);
FORCEPROP 1 LAST MATERIAL CHIP
J 0
(-2275 10825);
DISPLAY 0.638298 (-2275 10825);
DISPLAY INVISIBLE (-2275 10825);
FORCEPROP 2 LAST CDS_LIB pure_quanta
J 0
(-2000 10775);
DISPLAY INVISIBLE (-2000 10775);
FORCEPROP 1 LAST PATH I229
J 0
(-2050 10925);
DISPLAY 0.978723 (-2050 10925);
PAINT WHITE (-2050 10925);
DISPLAY INVISIBLE (-2050 10925);
FORCEPROP 1 LAST PART_NUMBER CS00002JB13
J 0
(-2150 10825);
DISPLAY 0.638298 (-2150 10825);
DISPLAY INVISIBLE (-2150 10825);
FORCEADD Q_RES..2
(-8925 9650);
FORCEPROP 1 LAST LOCATION R421
J 0
(-8875 9725);
DISPLAY 0.489362 (-8875 9725);
PAINT SKYBLUE (-8875 9725);
FORCEPROP 0 LAST $SEC 1
J 2
(-8875 9775);
DISPLAY 0.680851 (-8875 9775);
PAINT MONO (-8875 9775);
DISPLAY INVISIBLE (-8875 9775);
FORCEPROP 0 LAST CDS_SEC 1
J 2
(-8875 9775);
DISPLAY 1.021277 (-8875 9775);
DISPLAY INVISIBLE (-8875 9775);
FORCEPROP 1 LASTPIN (-8925 9750) $PN 1
J 0
(-8920 9712);
DISPLAY 0.489362 (-8920 9712);
PAINT MONO (-8920 9712);
FORCEPROP 1 LASTPIN (-8925 9550) $PN 2
J 0
(-8920 9560);
DISPLAY 0.489362 (-8920 9560);
PAINT MONO (-8920 9560);
FORCEPROP 1 LAST TOLERANCE 1%
J 0
(-8875 9675);
DISPLAY 0.489362 (-8875 9675);
PAINT SKYBLUE (-8875 9675);
FORCEPROP 1 LAST MATERIAL EMPTY
J 0
(-8875 9625);
DISPLAY 0.489362 (-8875 9625);
PAINT RED (-8875 9625);
FORCEPROP 1 LAST VALUE 1K
J 0
(-8875 9700);
DISPLAY 0.489362 (-8875 9700);
PAINT SKYBLUE (-8875 9700);
FORCEPROP 1 LAST PACK_TYPE 0402LF
J 0
(-8875 9600);
DISPLAY 0.489362 (-8875 9600);
PAINT SKYBLUE (-8875 9600);
DISPLAY INVISIBLE (-8875 9600);
FORCEPROP 1 LAST WATTAGE 1/16W
J 0
(-8875 9650);
DISPLAY 0.489362 (-8875 9650);
PAINT SKYBLUE (-8875 9650);
DISPLAY INVISIBLE (-8875 9650);
FORCEPROP 2 LAST CDS_LIB pure_quanta
J 2
(-8925 9650);
DISPLAY INVISIBLE (-8925 9650);
FORCEPROP 1 LAST PATH I23
J 0
(-8875 9825);
DISPLAY 0.978723 (-8875 9825);
PAINT WHITE (-8875 9825);
DISPLAY INVISIBLE (-8875 9825);
FORCEPROP 1 LAST PART_NUMBER CS21002FB06
J 0
(-8875 9575);
DISPLAY 0.489362 (-8875 9575);
PAINT SKYBLUE (-8875 9575);
DISPLAY INVISIBLE (-8875 9575);
FORCEADD Q_CAP..1
(-3900 8050);
FORCEPROP 1 LAST LOCATION C215
J 0
(-3850 8150);
DISPLAY 0.638298 (-3850 8150);
FORCEPROP 0 LAST $SEC 1
J 0
(-3850 8200);
DISPLAY 0.680851 (-3850 8200);
PAINT MONO (-3850 8200);
DISPLAY INVISIBLE (-3850 8200);
FORCEPROP 0 LAST CDS_SEC 1
J 0
(-3850 8200);
DISPLAY 0.680851 (-3850 8200);
DISPLAY INVISIBLE (-3850 8200);
FORCEPROP 1 LASTPIN (-3900 8150) $PN 1
J 0
(-3890 8130);
DISPLAY 0.787234 (-3890 8130);
PAINT MONO (-3890 8130);
FORCEPROP 1 LASTPIN (-3900 7950) $PN 2
J 0
(-3890 7930);
DISPLAY 0.787234 (-3890 7930);
PAINT MONO (-3890 7930);
FORCEPROP 1 LAST VOLTAGE 50V
J 0
(-3850 8050);
DISPLAY 0.638298 (-3850 8050);
FORCEPROP 1 LAST PACK_TYPE C0402
J 0
(-3850 7850);
DISPLAY 0.638298 (-3850 7850);
FORCEPROP 1 LAST MATERIAL NP0
J 0
(-3850 7950);
DISPLAY 0.638298 (-3850 7950);
FORCEPROP 1 LAST TOLERANCE 0.1P
J 0
(-3850 8000);
DISPLAY 0.638298 (-3850 8000);
FORCEPROP 1 LAST VALUE 8.2PF
J 0
(-3850 8100);
DISPLAY 0.638298 (-3850 8100);
FORCEPROP 2 LAST CDS_LIB pure_quanta
J 0
(-3900 8050);
DISPLAY INVISIBLE (-3900 8050);
FORCEPROP 1 LAST PATH I230
J 0
(-3850 8200);
DISPLAY 0.978723 (-3850 8200);
PAINT WHITE (-3850 8200);
DISPLAY INVISIBLE (-3850 8200);
FORCEPROP 1 LAST PART_NUMBER CH-8216TB09
J 0
(-3850 7900);
DISPLAY 0.638298 (-3850 7900);
DISPLAY INVISIBLE (-3850 7900);
FORCEADD Q_CAP..1
(-2800 8075);
FORCEPROP 1 LAST LOCATION C216
J 0
(-2750 8175);
DISPLAY 0.787234 (-2750 8175);
FORCEPROP 0 LAST $SEC 1
J 0
(-2750 8225);
DISPLAY 0.680851 (-2750 8225);
PAINT MONO (-2750 8225);
DISPLAY INVISIBLE (-2750 8225);
FORCEPROP 0 LAST CDS_SEC 1
J 0
(-2750 8225);
DISPLAY 0.680851 (-2750 8225);
DISPLAY INVISIBLE (-2750 8225);
FORCEPROP 1 LASTPIN (-2800 8175) $PN 1
J 0
(-2790 8155);
DISPLAY 0.787234 (-2790 8155);
PAINT MONO (-2790 8155);
FORCEPROP 1 LASTPIN (-2800 7975) $PN 2
J 0
(-2790 7955);
DISPLAY 0.787234 (-2790 7955);
PAINT MONO (-2790 7955);
FORCEPROP 1 LAST VOLTAGE 50V
J 0
(-2750 8075);
DISPLAY 0.638298 (-2750 8075);
FORCEPROP 1 LAST PACK_TYPE C0402
J 0
(-2750 7875);
DISPLAY 0.638298 (-2750 7875);
FORCEPROP 1 LAST MATERIAL NP0
J 0
(-2750 7975);
DISPLAY 0.638298 (-2750 7975);
FORCEPROP 1 LAST TOLERANCE 0.1P
J 0
(-2750 8025);
DISPLAY 0.638298 (-2750 8025);
FORCEPROP 1 LAST VALUE 8.2PF
J 0
(-2750 8125);
DISPLAY 0.638298 (-2750 8125);
FORCEPROP 2 LAST CDS_LIB pure_quanta
J 0
(-2800 8075);
DISPLAY INVISIBLE (-2800 8075);
FORCEPROP 1 LAST PATH I231
J 0
(-2750 8225);
DISPLAY 0.978723 (-2750 8225);
PAINT WHITE (-2750 8225);
DISPLAY INVISIBLE (-2750 8225);
FORCEPROP 1 LAST PART_NUMBER CH-8216TB09
J 0
(-2750 7925);
DISPLAY 0.638298 (-2750 7925);
DISPLAY INVISIBLE (-2750 7925);
FORCEADD Q_CAP..1
(-6225 7900);
FORCEPROP 1 LAST LOCATION C213
J 0
(-6175 8000);
DISPLAY 0.978723 (-6175 8000);
FORCEPROP 0 LAST $SEC 1
J 0
(-6175 8050);
DISPLAY 0.680851 (-6175 8050);
PAINT MONO (-6175 8050);
DISPLAY INVISIBLE (-6175 8050);
FORCEPROP 0 LAST CDS_SEC 1
J 0
(-6175 8050);
DISPLAY 0.680851 (-6175 8050);
DISPLAY INVISIBLE (-6175 8050);
FORCEPROP 1 LASTPIN (-6225 8000) $PN 1
J 0
(-6215 7980);
DISPLAY 0.787234 (-6215 7980);
PAINT MONO (-6215 7980);
FORCEPROP 1 LASTPIN (-6225 7800) $PN 2
J 0
(-6215 7780);
DISPLAY 0.787234 (-6215 7780);
PAINT MONO (-6215 7780);
FORCEPROP 1 LAST PACK_TYPE C0402
J 0
(-6175 7700);
DISPLAY 0.978723 (-6175 7700);
FORCEPROP 1 LAST VALUE 3.9P
J 0
(-6175 7950);
DISPLAY 0.978723 (-6175 7950);
FORCEPROP 1 LAST TOLERANCE 0.1P
J 0
(-6175 7850);
DISPLAY 0.978723 (-6175 7850);
FORCEPROP 1 LAST VOLTAGE 50V
J 0
(-6175 7900);
DISPLAY 0.978723 (-6175 7900);
FORCEPROP 1 LAST MATERIAL NPO
J 0
(-6175 7800);
DISPLAY 0.978723 (-6175 7800);
FORCEPROP 2 LAST CDS_LIB pure_quanta
J 0
(-6225 7900);
DISPLAY INVISIBLE (-6225 7900);
FORCEPROP 1 LAST PATH I232
J 0
(-6175 8050);
DISPLAY 0.978723 (-6175 8050);
PAINT WHITE (-6175 8050);
DISPLAY INVISIBLE (-6175 8050);
FORCEPROP 1 LAST PART_NUMBER CH-3916TB01
J 0
(-6175 7750);
DISPLAY 0.978723 (-6175 7750);
DISPLAY INVISIBLE (-6175 7750);
FORCEADD Q_CAP..1
(-4950 7900);
FORCEPROP 1 LAST LOCATION C214
J 0
(-4900 8000);
DISPLAY 0.978723 (-4900 8000);
FORCEPROP 0 LAST $SEC 1
J 0
(-4900 8050);
DISPLAY 0.680851 (-4900 8050);
PAINT MONO (-4900 8050);
DISPLAY INVISIBLE (-4900 8050);
FORCEPROP 0 LAST CDS_SEC 1
J 0
(-4900 8050);
DISPLAY 0.680851 (-4900 8050);
DISPLAY INVISIBLE (-4900 8050);
FORCEPROP 1 LASTPIN (-4950 8000) $PN 1
J 0
(-4940 7980);
DISPLAY 0.787234 (-4940 7980);
PAINT MONO (-4940 7980);
FORCEPROP 1 LASTPIN (-4950 7800) $PN 2
J 0
(-4940 7780);
DISPLAY 0.787234 (-4940 7780);
PAINT MONO (-4940 7780);
FORCEPROP 1 LAST PACK_TYPE C0402
J 0
(-4900 7700);
DISPLAY 0.978723 (-4900 7700);
FORCEPROP 1 LAST VALUE 3.9P
J 0
(-4900 7950);
DISPLAY 0.978723 (-4900 7950);
FORCEPROP 1 LAST MATERIAL NPO
J 0
(-4900 7800);
DISPLAY 0.978723 (-4900 7800);
FORCEPROP 1 LAST VOLTAGE 50V
J 0
(-4900 7900);
DISPLAY 0.978723 (-4900 7900);
FORCEPROP 1 LAST TOLERANCE 0.1P
J 0
(-4900 7850);
DISPLAY 0.978723 (-4900 7850);
FORCEPROP 2 LAST CDS_LIB pure_quanta
J 0
(-4950 7900);
DISPLAY INVISIBLE (-4950 7900);
FORCEPROP 1 LAST PATH I233
J 0
(-4900 8050);
DISPLAY 0.978723 (-4900 8050);
PAINT WHITE (-4900 8050);
DISPLAY INVISIBLE (-4900 8050);
FORCEPROP 1 LAST PART_NUMBER CH-3916TB01
J 0
(-4900 7750);
DISPLAY 0.978723 (-4900 7750);
DISPLAY INVISIBLE (-4900 7750);
FORCEADD Q_RES..2
(-8750 9650);
FORCEPROP 1 LAST LOCATION R423
J 0
(-8705 9725);
DISPLAY 0.489362 (-8705 9725);
PAINT SKYBLUE (-8705 9725);
FORCEPROP 0 LAST $SEC 1
J 0
(-8700 9800);
DISPLAY 0.680851 (-8700 9800);
PAINT MONO (-8700 9800);
DISPLAY INVISIBLE (-8700 9800);
FORCEPROP 0 LAST CDS_SEC 1
J 0
(-8700 9800);
DISPLAY 1.021277 (-8700 9800);
DISPLAY INVISIBLE (-8700 9800);
FORCEPROP 1 LASTPIN (-8750 9750) $PN 1
J 0
(-8745 9712);
DISPLAY 0.489362 (-8745 9712);
PAINT MONO (-8745 9712);
FORCEPROP 1 LASTPIN (-8750 9550) $PN 2
J 0
(-8745 9560);
DISPLAY 0.489362 (-8745 9560);
PAINT MONO (-8745 9560);
FORCEPROP 1 LAST TOLERANCE 1%
J 0
(-8700 9675);
DISPLAY 0.489362 (-8700 9675);
PAINT SKYBLUE (-8700 9675);
FORCEPROP 1 LAST MATERIAL EMPTY
J 0
(-8700 9625);
DISPLAY 0.489362 (-8700 9625);
PAINT RED (-8700 9625);
FORCEPROP 1 LAST VALUE 1K
J 0
(-8700 9700);
DISPLAY 0.489362 (-8700 9700);
PAINT SKYBLUE (-8700 9700);
FORCEPROP 1 LAST PACK_TYPE 0402LF
J 0
(-8700 9600);
DISPLAY 0.489362 (-8700 9600);
PAINT SKYBLUE (-8700 9600);
DISPLAY INVISIBLE (-8700 9600);
FORCEPROP 1 LAST WATTAGE 1/16W
J 0
(-8700 9650);
DISPLAY 0.489362 (-8700 9650);
PAINT SKYBLUE (-8700 9650);
DISPLAY INVISIBLE (-8700 9650);
FORCEPROP 2 LAST CDS_LIB pure_quanta
J 0
(-8750 9650);
DISPLAY INVISIBLE (-8750 9650);
FORCEPROP 1 LAST PATH I24
J 0
(-8700 9825);
DISPLAY 0.978723 (-8700 9825);
PAINT WHITE (-8700 9825);
DISPLAY INVISIBLE (-8700 9825);
FORCEPROP 1 LAST PART_NUMBER CS21002FB06
J 0
(-8700 9575);
DISPLAY 0.489362 (-8700 9575);
PAINT SKYBLUE (-8700 9575);
DISPLAY INVISIBLE (-8700 9575);
FORCEADD Q_RES..2
(-8575 9650);
FORCEPROP 1 LAST LOCATION R425
J 0
(-8530 9725);
DISPLAY 0.489362 (-8530 9725);
PAINT SKYBLUE (-8530 9725);
FORCEPROP 0 LAST $SEC 1
J 0
(-8525 9800);
DISPLAY 0.680851 (-8525 9800);
PAINT MONO (-8525 9800);
DISPLAY INVISIBLE (-8525 9800);
FORCEPROP 0 LAST CDS_SEC 1
J 0
(-8525 9800);
DISPLAY 1.021277 (-8525 9800);
DISPLAY INVISIBLE (-8525 9800);
FORCEPROP 1 LASTPIN (-8575 9750) $PN 1
J 0
(-8570 9712);
DISPLAY 0.489362 (-8570 9712);
PAINT MONO (-8570 9712);
FORCEPROP 1 LASTPIN (-8575 9550) $PN 2
J 0
(-8570 9560);
DISPLAY 0.489362 (-8570 9560);
PAINT MONO (-8570 9560);
FORCEPROP 1 LAST TOLERANCE 1%
J 0
(-8525 9675);
DISPLAY 0.489362 (-8525 9675);
PAINT SKYBLUE (-8525 9675);
FORCEPROP 1 LAST MATERIAL EMPTY
J 0
(-8525 9625);
DISPLAY 0.489362 (-8525 9625);
PAINT RED (-8525 9625);
FORCEPROP 1 LAST VALUE 1K
J 0
(-8525 9700);
DISPLAY 0.489362 (-8525 9700);
PAINT SKYBLUE (-8525 9700);
FORCEPROP 2 LAST CDS_LIB pure_quanta
J 0
(-8575 9650);
DISPLAY INVISIBLE (-8575 9650);
FORCEPROP 1 LAST PACK_TYPE 0402LF
J 0
(-8525 9600);
DISPLAY 0.489362 (-8525 9600);
PAINT SKYBLUE (-8525 9600);
DISPLAY INVISIBLE (-8525 9600);
FORCEPROP 1 LAST WATTAGE 1/16W
J 0
(-8525 9650);
DISPLAY 0.489362 (-8525 9650);
PAINT SKYBLUE (-8525 9650);
DISPLAY INVISIBLE (-8525 9650);
FORCEPROP 1 LAST PATH I25
J 0
(-8525 9825);
DISPLAY 0.978723 (-8525 9825);
PAINT WHITE (-8525 9825);
DISPLAY INVISIBLE (-8525 9825);
FORCEPROP 1 LAST PART_NUMBER CS21002FB06
J 0
(-8525 9575);
DISPLAY 0.489362 (-8525 9575);
PAINT SKYBLUE (-8525 9575);
DISPLAY INVISIBLE (-8525 9575);
FORCEADD VCC_CORE..1
(-8575 9950);
FORCEPROP 3 LASTPIN (-8575 9900) SIG_NAME PVDD11_S3_P0\g
J 0
(-8565 9910);
DISPLAY 0.659574 (-8565 9910);
PAINT MONO (-8565 9910);
DISPLAY INVISIBLE (-8565 9910);
FORCEPROP 1 LAST HDL_POWER PVDD11_S3_P0
J 1
(-8575 10000);
DISPLAY 0.489362 (-8575 10000);
PAINT GREEN (-8575 10000);
FORCEPROP 2 LAST CDS_LIB pure_quanta_power
J 0
(-8575 9950);
DISPLAY INVISIBLE (-8575 9950);
FORCEPROP 1 LAST PATH I26
J 0
(-8525 9975);
DISPLAY 0.872340 (-8525 9975);
PAINT AQUA (-8525 9975);
DISPLAY INVISIBLE (-8525 9975);
FORCEADD UNIVERSAL_GND..1
(-9125 11950);
FORCEPROP 3 LASTPIN (-9125 12000) SIG_NAME GND\g
J 0
(-9115 12010);
DISPLAY 0.659574 (-9115 12010);
PAINT MONO (-9115 12010);
DISPLAY INVISIBLE (-9115 12010);
FORCEPROP 2 LAST CDS_LIB pure_quanta_power
J 2
(-9125 11950);
DISPLAY INVISIBLE (-9125 11950);
FORCEPROP 1 LAST HDL_POWER GND
J 1
(-9100 11875);
DISPLAY 0.702128 (-9100 11875);
PAINT GREEN (-9100 11875);
DISPLAY INVISIBLE (-9100 11875);
FORCEPROP 1 LAST PATH I27
J 0
(-9050 11950);
DISPLAY 0.872340 (-9050 11950);
PAINT AQUA (-9050 11950);
DISPLAY INVISIBLE (-9050 11950);
FORCEADD CONN6_HBC1031L200D8H..1
R 2
(-8750 12225);
FORCEPROP 1 LAST LOCATION J6
J 0
(-8875 12450);
DISPLAY 0.489362 (-8875 12450);
PAINT SKYBLUE (-8875 12450);
FORCEPROP 2 LAST $SEC 1
J 0
(-8875 12700);
DISPLAY 0.680851 (-8875 12700);
PAINT MONO (-8875 12700);
DISPLAY INVISIBLE (-8875 12700);
FORCEPROP 0 LAST CDS_SEC 1
J 0
(-8875 12700);
DISPLAY 1.021277 (-8875 12700);
DISPLAY INVISIBLE (-8875 12700);
FORCEPROP 2 LASTPIN (-8475 12325) $PN 1
J 0
(-8465 12335);
DISPLAY 0.489362 (-8465 12335);
PAINT MONO (-8465 12335);
FORCEPROP 2 LASTPIN (-9025 12325) $PN 2
J 2
(-9035 12335);
DISPLAY 0.489362 (-9035 12335);
PAINT MONO (-9035 12335);
FORCEPROP 2 LASTPIN (-8475 12225) $PN 3
J 0
(-8465 12235);
DISPLAY 0.489362 (-8465 12235);
PAINT MONO (-8465 12235);
FORCEPROP 2 LASTPIN (-9025 12225) $PN 4
J 2
(-9035 12235);
DISPLAY 0.489362 (-9035 12235);
PAINT MONO (-9035 12235);
FORCEPROP 2 LASTPIN (-8475 12125) $PN 5
J 0
(-8465 12135);
DISPLAY 0.489362 (-8465 12135);
PAINT MONO (-8465 12135);
FORCEPROP 2 LASTPIN (-9025 12125) $PN 6
J 2
(-9035 12135);
DISPLAY 0.489362 (-9035 12135);
PAINT MONO (-9035 12135);
FORCEPROP 2 LAST VALUE CONN6_HBC1031-L200D-8H
J 0
(-8875 12600);
DISPLAY 0.489362 (-8875 12600);
PAINT SKYBLUE (-8875 12600);
FORCEPROP 1 LAST MATERIAL IO
J 0
(-8875 12382);
DISPLAY 0.489362 (-8875 12382);
PAINT SKYBLUE (-8875 12382);
FORCEPROP 2 LAST PART_TYPE THLF
J 0
(-8875 12650);
DISPLAY 1.021277 (-8875 12650);
FORCEPROP 1 LAST CDS_LMAN_SYM_OUTLINE -125,150,125,-150
J 2
(-8750 12225);
DISPLAY 0.468085 (-8750 12225);
PAINT GREEN (-8750 12225);
DISPLAY INVISIBLE (-8750 12225);
FORCEPROP 1 LAST NEEDS_NO_SIZE TRUE
J 2
(-8750 12225);
DISPLAY 0.723404 (-8750 12225);
PAINT GREEN (-8750 12225);
DISPLAY INVISIBLE (-8750 12225);
FORCEPROP 2 LAST CDS_LIB pure_quanta
J 0
(-8750 12225);
DISPLAY INVISIBLE (-8750 12225);
FORCEPROP 1 LAST PATH I28
J 2
(-8750 12225);
DISPLAY 0.723404 (-8750 12225);
PAINT GREEN (-8750 12225);
DISPLAY INVISIBLE (-8750 12225);
FORCEPROP 1 LAST PART_NUMBER DFHD06MS263
J 0
(-8875 12509);
DISPLAY 0.489362 (-8875 12509);
PAINT SKYBLUE (-8875 12509);
DISPLAY INVISIBLE (-8875 12509);
FORCEADD Q_RES..2
(-8775 13050);
FORCEPROP 1 LAST LOCATION R422
J 0
(-8925 13150);
DISPLAY 0.489362 (-8925 13150);
PAINT SKYBLUE (-8925 13150);
FORCEPROP 0 LAST $SEC 1
J 0
(-8725 13200);
DISPLAY 0.680851 (-8725 13200);
PAINT MONO (-8725 13200);
DISPLAY INVISIBLE (-8725 13200);
FORCEPROP 0 LAST CDS_SEC 1
J 0
(-8725 13200);
DISPLAY 1.021277 (-8725 13200);
DISPLAY INVISIBLE (-8725 13200);
FORCEPROP 1 LASTPIN (-8775 13150) $PN 1
J 0
(-8770 13112);
DISPLAY 0.489362 (-8770 13112);
PAINT MONO (-8770 13112);
FORCEPROP 1 LASTPIN (-8775 12950) $PN 2
J 0
(-8770 12960);
DISPLAY 0.489362 (-8770 12960);
PAINT MONO (-8770 12960);
FORCEPROP 1 LAST VALUE 2.2K
J 0
(-8925 13100);
DISPLAY 0.489362 (-8925 13100);
PAINT SKYBLUE (-8925 13100);
FORCEPROP 1 LAST PACK_TYPE 0402LF
J 0
(-8725 13000);
DISPLAY 0.489362 (-8725 13000);
PAINT SKYBLUE (-8725 13000);
DISPLAY INVISIBLE (-8725 13000);
FORCEPROP 1 LAST WATTAGE 1/16W
J 0
(-8725 13050);
DISPLAY 0.489362 (-8725 13050);
PAINT SKYBLUE (-8725 13050);
DISPLAY INVISIBLE (-8725 13050);
FORCEPROP 2 LAST CDS_LIB pure_quanta
J 0
(-8775 13050);
DISPLAY INVISIBLE (-8775 13050);
FORCEPROP 1 LAST TOLERANCE 5%
J 0
(-8725 13075);
DISPLAY 0.489362 (-8725 13075);
PAINT SKYBLUE (-8725 13075);
DISPLAY INVISIBLE (-8725 13075);
FORCEPROP 1 LAST MATERIAL CHIP
J 0
(-8925 13050);
DISPLAY 0.489362 (-8925 13050);
PAINT SKYBLUE (-8925 13050);
DISPLAY INVISIBLE (-8925 13050);
FORCEPROP 1 LAST PATH I29
J 0
(-8725 13225);
DISPLAY 0.978723 (-8725 13225);
PAINT WHITE (-8725 13225);
DISPLAY INVISIBLE (-8725 13225);
FORCEPROP 1 LAST PART_NUMBER CS22202JB07
J 0
(-9050 13050);
DISPLAY 0.489362 (-9050 13050);
PAINT SKYBLUE (-9050 13050);
DISPLAY INVISIBLE (-9050 13050);
FORCEADD OFFPAGE..2
R 2
(-8775 7500);
FORCEPROP 2 LAST $XR1 28 
J 0
(-9089 7500);
DISPLAY 0.638298 (-9089 7500);
PAINT MONO (-9089 7500);
FORCEPROP 2 LAST $XR0 82 
J 0
(-8999 7500);
DISPLAY 0.638298 (-8999 7500);
PAINT MONO (-8999 7500);
FORCEPROP 2 LAST CDS_LIB standard
J 0
(-8775 7500);
DISPLAY INVISIBLE (-8775 7500);
FORCEPROP 1 LAST OFFPAGE TRUE
J 2
(-9100 7375);
DISPLAY 0.872340 (-9100 7375);
PAINT GREEN (-9100 7375);
DISPLAY INVISIBLE (-9100 7375);
FORCEPROP 1 LAST COMMENT_BODY TRUE
J 2
(-8730 7405);
DISPLAY 0.872340 (-8730 7405);
PAINT GREEN (-8730 7405);
DISPLAY INVISIBLE (-8730 7405);
FORCEPROP 2 LAST PATH I3
J 0
(-8725 7575);
DISPLAY 0.680851 (-8725 7575);
DISPLAY INVISIBLE (-8725 7575);
FORCEADD Q_RES..2
(-8600 13050);
FORCEPROP 1 LAST LOCATION R424
J 0
(-8550 13175);
DISPLAY 0.489362 (-8550 13175);
PAINT SKYBLUE (-8550 13175);
FORCEPROP 0 LAST $SEC 1
J 0
(-8550 13200);
DISPLAY 0.680851 (-8550 13200);
PAINT MONO (-8550 13200);
DISPLAY INVISIBLE (-8550 13200);
FORCEPROP 0 LAST CDS_SEC 1
J 0
(-8550 13200);
DISPLAY 0.680851 (-8550 13200);
DISPLAY INVISIBLE (-8550 13200);
FORCEPROP 1 LASTPIN (-8600 13150) $PN 1
J 0
(-8595 13112);
DISPLAY 0.489362 (-8595 13112);
PAINT MONO (-8595 13112);
FORCEPROP 1 LASTPIN (-8600 12950) $PN 2
J 0
(-8595 12960);
DISPLAY 0.489362 (-8595 12960);
PAINT MONO (-8595 12960);
FORCEPROP 1 LAST VALUE 2.2K
J 0
(-8550 13125);
DISPLAY 0.489362 (-8550 13125);
PAINT SKYBLUE (-8550 13125);
FORCEPROP 2 LAST CDS_LIB pure_quanta
J 0
(-8600 13050);
DISPLAY INVISIBLE (-8600 13050);
FORCEPROP 1 LAST WATTAGE 1/16W
J 0
(-8560 13025);
DISPLAY 0.510638 (-8560 13025);
PAINT SKYBLUE (-8560 13025);
DISPLAY INVISIBLE (-8560 13025);
FORCEPROP 1 LAST MATERIAL CHIP
J 0
(-8560 12975);
DISPLAY 0.510638 (-8560 12975);
PAINT SKYBLUE (-8560 12975);
DISPLAY INVISIBLE (-8560 12975);
FORCEPROP 1 LAST TOLERANCE 5%
J 0
(-8555 13075);
DISPLAY 0.510638 (-8555 13075);
PAINT SKYBLUE (-8555 13075);
DISPLAY INVISIBLE (-8555 13075);
FORCEPROP 1 LAST PACK_TYPE 0402LF
J 0
(-8550 13025);
DISPLAY 0.489362 (-8550 13025);
PAINT SKYBLUE (-8550 13025);
DISPLAY INVISIBLE (-8550 13025);
FORCEPROP 1 LAST PATH I30
J 0
(-8550 13225);
DISPLAY 0.978723 (-8550 13225);
PAINT WHITE (-8550 13225);
DISPLAY INVISIBLE (-8550 13225);
FORCEPROP 1 LAST PART_NUMBER CS22202JB07
J 0
(-8550 13075);
DISPLAY 0.489362 (-8550 13075);
PAINT SKYBLUE (-8550 13075);
DISPLAY INVISIBLE (-8550 13075);
FORCEADD UNIVERSAL_POWER..1
(-8600 13350);
FORCEPROP 3 LASTPIN (-8600 13300) SIG_NAME PVDD18_S5_P0\g
J 0
(-8590 13310);
DISPLAY 0.659574 (-8590 13310);
PAINT MONO (-8590 13310);
DISPLAY INVISIBLE (-8590 13310);
FORCEPROP 1 LAST HDL_POWER PVDD18_S5_P0
J 1
(-8600 13400);
DISPLAY 0.489362 (-8600 13400);
PAINT GREEN (-8600 13400);
FORCEPROP 2 LAST CDS_LIB pure_quanta_power
J 0
(-8600 13350);
DISPLAY INVISIBLE (-8600 13350);
FORCEPROP 1 LAST PATH I31
J 0
(-8550 13375);
DISPLAY 0.872340 (-8550 13375);
PAINT AQUA (-8550 13375);
DISPLAY INVISIBLE (-8550 13375);
FORCEADD UNIVERSAL_GND..1
(-7900 7075);
FORCEPROP 3 LASTPIN (-7900 7125) SIG_NAME GND\g
J 0
(-7890 7135);
DISPLAY 0.659574 (-7890 7135);
PAINT MONO (-7890 7135);
DISPLAY INVISIBLE (-7890 7135);
FORCEPROP 2 LAST CDS_LIB pure_quanta_power
J 0
(-7900 7075);
DISPLAY INVISIBLE (-7900 7075);
FORCEPROP 1 LAST HDL_POWER GND
J 1
(-7875 7000);
DISPLAY 0.872340 (-7875 7000);
PAINT GREEN (-7875 7000);
DISPLAY INVISIBLE (-7875 7000);
FORCEPROP 1 LAST PATH I32
J 0
(-7825 7075);
DISPLAY 0.872340 (-7825 7075);
PAINT AQUA (-7825 7075);
DISPLAY INVISIBLE (-7825 7075);
FORCEADD Q_RES..1
R 1
(-7900 7225);
FORCEPROP 1 LAST LOCATION R582
J 0
(-7875 7125);
DISPLAY 0.489362 (-7875 7125);
PAINT SKYBLUE (-7875 7125);
FORCEPROP 0 LAST $SEC 1
R 1
J 0
(-7875 7275);
DISPLAY 0.680851 (-7875 7275);
PAINT MONO (-7875 7275);
DISPLAY INVISIBLE (-7875 7275);
FORCEPROP 0 LAST CDS_SEC 1
R 1
J 0
(-7875 7275);
DISPLAY 1.021277 (-7875 7275);
DISPLAY INVISIBLE (-7875 7275);
FORCEPROP 1 LASTPIN (-7900 7125) $PN 1
R 1
J 0
(-7912 7137);
DISPLAY 0.489362 (-7912 7137);
PAINT MONO (-7912 7137);
FORCEPROP 1 LASTPIN (-7900 7325) $PN 2
R 1
J 0
(-7912 7287);
DISPLAY 0.489362 (-7912 7287);
PAINT MONO (-7912 7287);
FORCEPROP 1 LAST VALUE 4.7K
J 0
(-7875 7200);
DISPLAY 0.489362 (-7875 7200);
PAINT SKYBLUE (-7875 7200);
FORCEPROP 1 LAST MATERIAL EMPTY
J 0
(-7875 7250);
DISPLAY 0.489362 (-7875 7250);
PAINT RED (-7875 7250);
FORCEPROP 2 LAST CDS_LIB pure_quanta
R 1
J 0
(-7900 7225);
DISPLAY INVISIBLE (-7900 7225);
FORCEPROP 1 LAST WATTAGE 1/16W
R 1
J 2
(-7750 7200);
DISPLAY 0.978723 (-7750 7200);
PAINT SKYBLUE (-7750 7200);
DISPLAY INVISIBLE (-7750 7200);
FORCEPROP 1 LAST TOLERANCE 5%
R 1
J 0
(-7800 7225);
DISPLAY 0.978723 (-7800 7225);
PAINT SKYBLUE (-7800 7225);
DISPLAY INVISIBLE (-7800 7225);
FORCEPROP 1 LAST PACK_TYPE 0402LF
R 1
J 0
(-7750 7475);
DISPLAY 0.978723 (-7750 7475);
PAINT SKYBLUE (-7750 7475);
DISPLAY INVISIBLE (-7750 7475);
FORCEPROP 1 LAST PATH I33
R 1
J 0
(-8050 7175);
DISPLAY 0.978723 (-8050 7175);
PAINT WHITE (-8050 7175);
DISPLAY INVISIBLE (-8050 7175);
FORCEPROP 1 LAST PART_NUMBER CS24702JB10
R 1
J 0
(-8000 7175);
DISPLAY 0.978723 (-8000 7175);
PAINT SKYBLUE (-8000 7175);
DISPLAY INVISIBLE (-8000 7175);
FORCEADD Q_RES..1
R 1
(-7900 7775);
FORCEPROP 1 LAST LOCATION R581
J 0
(-7875 7700);
DISPLAY 0.489362 (-7875 7700);
PAINT SKYBLUE (-7875 7700);
FORCEPROP 0 LAST $SEC 1
R 1
J 0
(-7875 7825);
DISPLAY 0.680851 (-7875 7825);
PAINT MONO (-7875 7825);
DISPLAY INVISIBLE (-7875 7825);
FORCEPROP 0 LAST CDS_SEC 1
R 1
J 0
(-7875 7825);
DISPLAY 1.021277 (-7875 7825);
DISPLAY INVISIBLE (-7875 7825);
FORCEPROP 1 LASTPIN (-7900 7675) $PN 1
R 1
J 0
(-7912 7687);
DISPLAY 0.489362 (-7912 7687);
PAINT MONO (-7912 7687);
FORCEPROP 1 LASTPIN (-7900 7875) $PN 2
R 1
J 0
(-7912 7837);
DISPLAY 0.489362 (-7912 7837);
PAINT MONO (-7912 7837);
FORCEPROP 1 LAST VALUE 4.7K
J 0
(-7875 7750);
DISPLAY 0.489362 (-7875 7750);
PAINT SKYBLUE (-7875 7750);
FORCEPROP 1 LAST MATERIAL EMPTY
J 0
(-7875 7800);
DISPLAY 0.489362 (-7875 7800);
PAINT RED (-7875 7800);
FORCEPROP 2 LAST CDS_LIB pure_quanta
J 0
(-7900 7775);
DISPLAY INVISIBLE (-7900 7775);
FORCEPROP 1 LAST WATTAGE 1/16W
R 1
J 2
(-7750 7750);
DISPLAY 0.978723 (-7750 7750);
PAINT SKYBLUE (-7750 7750);
DISPLAY INVISIBLE (-7750 7750);
FORCEPROP 1 LAST TOLERANCE 5%
R 1
J 0
(-7800 7775);
DISPLAY 0.978723 (-7800 7775);
PAINT SKYBLUE (-7800 7775);
DISPLAY INVISIBLE (-7800 7775);
FORCEPROP 1 LAST PACK_TYPE 0402LF
R 1
J 0
(-7750 8025);
DISPLAY 0.978723 (-7750 8025);
PAINT SKYBLUE (-7750 8025);
DISPLAY INVISIBLE (-7750 8025);
FORCEPROP 1 LAST PATH I34
R 1
J 0
(-8050 7725);
DISPLAY 0.978723 (-8050 7725);
PAINT WHITE (-8050 7725);
DISPLAY INVISIBLE (-8050 7725);
FORCEPROP 1 LAST PART_NUMBER CS24702JB10
R 1
J 0
(-8000 7725);
DISPLAY 0.978723 (-8000 7725);
PAINT SKYBLUE (-8000 7725);
DISPLAY INVISIBLE (-8000 7725);
FORCEADD UNIVERSAL_GND..1
(-7625 7075);
FORCEPROP 3 LASTPIN (-7625 7125) SIG_NAME GND\g
J 0
(-7615 7135);
DISPLAY 0.659574 (-7615 7135);
PAINT MONO (-7615 7135);
DISPLAY INVISIBLE (-7615 7135);
FORCEPROP 2 LAST CDS_LIB pure_quanta_power
J 0
(-7625 7075);
DISPLAY INVISIBLE (-7625 7075);
FORCEPROP 1 LAST HDL_POWER GND
J 1
(-7600 7000);
DISPLAY 0.872340 (-7600 7000);
PAINT GREEN (-7600 7000);
DISPLAY INVISIBLE (-7600 7000);
FORCEPROP 1 LAST PATH I35
J 0
(-7550 7075);
DISPLAY 0.872340 (-7550 7075);
PAINT AQUA (-7550 7075);
DISPLAY INVISIBLE (-7550 7075);
FORCEADD Q_RES..1
R 1
(-7625 7225);
FORCEPROP 1 LAST LOCATION R287
J 0
(-7600 7150);
DISPLAY 0.489362 (-7600 7150);
PAINT SKYBLUE (-7600 7150);
FORCEPROP 2 LAST $SEC 1
J 0
(-7600 7275);
DISPLAY 0.680851 (-7600 7275);
PAINT MONO (-7600 7275);
DISPLAY INVISIBLE (-7600 7275);
FORCEPROP 2 LAST CDS_SEC 1
J 0
(-7600 7275);
DISPLAY 1.021277 (-7600 7275);
DISPLAY INVISIBLE (-7600 7275);
FORCEPROP 1 LASTPIN (-7625 7125) $PN 1
R 1
J 0
(-7637 7137);
DISPLAY 0.489362 (-7637 7137);
PAINT MONO (-7637 7137);
FORCEPROP 1 LASTPIN (-7625 7325) $PN 2
R 1
J 0
(-7637 7287);
DISPLAY 0.489362 (-7637 7287);
PAINT MONO (-7637 7287);
FORCEPROP 1 LAST VALUE 4.7K
J 0
(-7600 7200);
DISPLAY 0.489362 (-7600 7200);
PAINT SKYBLUE (-7600 7200);
FORCEPROP 1 LAST MATERIAL EMPTY
J 0
(-7600 7250);
DISPLAY 0.489362 (-7600 7250);
PAINT RED (-7600 7250);
FORCEPROP 2 LAST CDS_LIB pure_quanta
J 0
(-7625 7225);
DISPLAY INVISIBLE (-7625 7225);
FORCEPROP 1 LAST WATTAGE 1/16W
R 1
J 2
(-7475 7200);
DISPLAY 0.978723 (-7475 7200);
PAINT SKYBLUE (-7475 7200);
DISPLAY INVISIBLE (-7475 7200);
FORCEPROP 1 LAST TOLERANCE 5%
R 1
J 0
(-7525 7225);
DISPLAY 0.978723 (-7525 7225);
PAINT SKYBLUE (-7525 7225);
DISPLAY INVISIBLE (-7525 7225);
FORCEPROP 1 LAST PACK_TYPE 0402LF
R 1
J 0
(-7475 7475);
DISPLAY 0.978723 (-7475 7475);
PAINT SKYBLUE (-7475 7475);
DISPLAY INVISIBLE (-7475 7475);
FORCEPROP 1 LAST PATH I36
R 1
J 0
(-7775 7175);
DISPLAY 0.978723 (-7775 7175);
PAINT WHITE (-7775 7175);
DISPLAY INVISIBLE (-7775 7175);
FORCEPROP 1 LAST PART_NUMBER CS24702JB10
R 1
J 0
(-7725 7175);
DISPLAY 0.978723 (-7725 7175);
PAINT SKYBLUE (-7725 7175);
DISPLAY INVISIBLE (-7725 7175);
FORCEADD Q_RES..1
R 1
(-7400 7225);
FORCEPROP 1 LAST LOCATION R440
J 0
(-7375 7150);
DISPLAY 0.489362 (-7375 7150);
PAINT SKYBLUE (-7375 7150);
FORCEPROP 2 LAST $SEC 1
J 0
(-7375 7275);
DISPLAY 0.680851 (-7375 7275);
PAINT MONO (-7375 7275);
DISPLAY INVISIBLE (-7375 7275);
FORCEPROP 2 LAST CDS_SEC 1
J 0
(-7375 7275);
DISPLAY 1.021277 (-7375 7275);
DISPLAY INVISIBLE (-7375 7275);
FORCEPROP 1 LASTPIN (-7400 7125) $PN 1
R 1
J 0
(-7412 7137);
DISPLAY 0.489362 (-7412 7137);
PAINT MONO (-7412 7137);
FORCEPROP 1 LASTPIN (-7400 7325) $PN 2
R 1
J 0
(-7412 7287);
DISPLAY 0.489362 (-7412 7287);
PAINT MONO (-7412 7287);
FORCEPROP 1 LAST VALUE 4.7K
J 0
(-7375 7200);
DISPLAY 0.489362 (-7375 7200);
PAINT SKYBLUE (-7375 7200);
FORCEPROP 1 LAST MATERIAL EMPTY
J 0
(-7375 7250);
DISPLAY 0.489362 (-7375 7250);
PAINT RED (-7375 7250);
FORCEPROP 1 LAST PACK_TYPE 0402LF
R 1
J 0
(-7250 7475);
DISPLAY 0.978723 (-7250 7475);
PAINT SKYBLUE (-7250 7475);
DISPLAY INVISIBLE (-7250 7475);
FORCEPROP 1 LAST TOLERANCE 5%
R 1
J 0
(-7300 7225);
DISPLAY 0.978723 (-7300 7225);
PAINT SKYBLUE (-7300 7225);
DISPLAY INVISIBLE (-7300 7225);
FORCEPROP 1 LAST WATTAGE 1/16W
R 1
J 2
(-7250 7200);
DISPLAY 0.978723 (-7250 7200);
PAINT SKYBLUE (-7250 7200);
DISPLAY INVISIBLE (-7250 7200);
FORCEPROP 2 LAST CDS_LIB pure_quanta
J 0
(-7400 7225);
DISPLAY INVISIBLE (-7400 7225);
FORCEPROP 1 LAST PATH I37
R 1
J 0
(-7550 7175);
DISPLAY 0.978723 (-7550 7175);
PAINT WHITE (-7550 7175);
DISPLAY INVISIBLE (-7550 7175);
FORCEPROP 1 LAST PART_NUMBER CS24702JB10
R 1
J 0
(-7500 7175);
DISPLAY 0.978723 (-7500 7175);
PAINT SKYBLUE (-7500 7175);
DISPLAY INVISIBLE (-7500 7175);
FORCEADD UNIVERSAL_GND..1
(-7400 7075);
FORCEPROP 3 LASTPIN (-7400 7125) SIG_NAME GND\g
J 0
(-7390 7135);
DISPLAY 0.659574 (-7390 7135);
PAINT MONO (-7390 7135);
DISPLAY INVISIBLE (-7390 7135);
FORCEPROP 2 LAST CDS_LIB pure_quanta_power
J 0
(-7400 7075);
DISPLAY INVISIBLE (-7400 7075);
FORCEPROP 1 LAST HDL_POWER GND
J 1
(-7375 7000);
DISPLAY 0.872340 (-7375 7000);
PAINT GREEN (-7375 7000);
DISPLAY INVISIBLE (-7375 7000);
FORCEPROP 1 LAST PATH I38
J 0
(-7325 7075);
DISPLAY 0.872340 (-7325 7075);
PAINT AQUA (-7325 7075);
DISPLAY INVISIBLE (-7325 7075);
FORCEADD UNIVERSAL_GND..1
(-7225 7075);
FORCEPROP 3 LASTPIN (-7225 7125) SIG_NAME GND\g
J 0
(-7215 7135);
DISPLAY 0.659574 (-7215 7135);
PAINT MONO (-7215 7135);
DISPLAY INVISIBLE (-7215 7135);
FORCEPROP 2 LAST CDS_LIB pure_quanta_power
J 0
(-7225 7075);
DISPLAY INVISIBLE (-7225 7075);
FORCEPROP 1 LAST HDL_POWER GND
J 1
(-7200 7000);
DISPLAY 0.872340 (-7200 7000);
PAINT GREEN (-7200 7000);
DISPLAY INVISIBLE (-7200 7000);
FORCEPROP 1 LAST PATH I39
J 0
(-7150 7075);
DISPLAY 0.872340 (-7150 7075);
PAINT AQUA (-7150 7075);
DISPLAY INVISIBLE (-7150 7075);
FORCEADD OFFPAGE..2
R 2
(-8775 7450);
FORCEPROP 2 LAST $XR1 28 
J 0
(-9089 7450);
DISPLAY 0.638298 (-9089 7450);
PAINT MONO (-9089 7450);
FORCEPROP 2 LAST $XR0 82 
J 0
(-8999 7450);
DISPLAY 0.638298 (-8999 7450);
PAINT MONO (-8999 7450);
FORCEPROP 2 LAST CDS_LIB standard
J 0
(-8775 7450);
DISPLAY INVISIBLE (-8775 7450);
FORCEPROP 1 LAST OFFPAGE TRUE
J 2
(-9100 7325);
DISPLAY 0.872340 (-9100 7325);
PAINT GREEN (-9100 7325);
DISPLAY INVISIBLE (-9100 7325);
FORCEPROP 1 LAST COMMENT_BODY TRUE
J 2
(-8730 7355);
DISPLAY 0.872340 (-8730 7355);
PAINT GREEN (-8730 7355);
DISPLAY INVISIBLE (-8730 7355);
FORCEPROP 2 LAST PATH I4
J 0
(-8725 7525);
DISPLAY 0.680851 (-8725 7525);
DISPLAY INVISIBLE (-8725 7525);
FORCEADD Q_RES..1
R 1
(-7225 7225);
FORCEPROP 1 LAST LOCATION R5026
J 0
(-7200 7150);
DISPLAY 0.489362 (-7200 7150);
PAINT SKYBLUE (-7200 7150);
FORCEPROP 2 LAST $SEC 1
J 0
(-7200 7275);
DISPLAY 0.680851 (-7200 7275);
PAINT MONO (-7200 7275);
DISPLAY INVISIBLE (-7200 7275);
FORCEPROP 2 LAST CDS_SEC 1
J 0
(-7200 7275);
DISPLAY 1.021277 (-7200 7275);
DISPLAY INVISIBLE (-7200 7275);
FORCEPROP 1 LASTPIN (-7225 7125) $PN 1
R 1
J 0
(-7237 7137);
DISPLAY 0.489362 (-7237 7137);
PAINT MONO (-7237 7137);
FORCEPROP 1 LASTPIN (-7225 7325) $PN 2
R 1
J 0
(-7237 7287);
DISPLAY 0.489362 (-7237 7287);
PAINT MONO (-7237 7287);
FORCEPROP 1 LAST MATERIAL EMPTY
J 0
(-7200 7250);
DISPLAY 0.489362 (-7200 7250);
PAINT RED (-7200 7250);
FORCEPROP 1 LAST VALUE 4.7K
J 0
(-7200 7200);
DISPLAY 0.489362 (-7200 7200);
PAINT SKYBLUE (-7200 7200);
FORCEPROP 1 LAST PACK_TYPE 0402LF
R 1
J 0
(-7075 7475);
DISPLAY 0.978723 (-7075 7475);
PAINT SKYBLUE (-7075 7475);
DISPLAY INVISIBLE (-7075 7475);
FORCEPROP 1 LAST TOLERANCE 5%
R 1
J 0
(-7125 7225);
DISPLAY 0.978723 (-7125 7225);
PAINT SKYBLUE (-7125 7225);
DISPLAY INVISIBLE (-7125 7225);
FORCEPROP 1 LAST WATTAGE 1/16W
R 1
J 2
(-7075 7200);
DISPLAY 0.978723 (-7075 7200);
PAINT SKYBLUE (-7075 7200);
DISPLAY INVISIBLE (-7075 7200);
FORCEPROP 2 LAST CDS_LIB pure_quanta
J 0
(-7225 7225);
DISPLAY INVISIBLE (-7225 7225);
FORCEPROP 1 LAST PATH I40
R 1
J 0
(-7375 7175);
DISPLAY 0.978723 (-7375 7175);
PAINT WHITE (-7375 7175);
DISPLAY INVISIBLE (-7375 7175);
FORCEPROP 1 LAST PART_NUMBER CS24702JB10
R 1
J 0
(-7325 7175);
DISPLAY 0.978723 (-7325 7175);
PAINT SKYBLUE (-7325 7175);
DISPLAY INVISIBLE (-7325 7175);
FORCEADD Q_RES..1
R 1
(-7625 7750);
FORCEPROP 1 LAST LOCATION R276
J 0
(-7600 7675);
DISPLAY 0.489362 (-7600 7675);
PAINT SKYBLUE (-7600 7675);
FORCEPROP 2 LAST $SEC 1
J 0
(-7600 7800);
DISPLAY 0.680851 (-7600 7800);
PAINT MONO (-7600 7800);
DISPLAY INVISIBLE (-7600 7800);
FORCEPROP 2 LAST CDS_SEC 1
J 0
(-7600 7800);
DISPLAY 1.021277 (-7600 7800);
DISPLAY INVISIBLE (-7600 7800);
FORCEPROP 1 LASTPIN (-7625 7650) $PN 1
R 1
J 0
(-7637 7662);
DISPLAY 0.489362 (-7637 7662);
PAINT MONO (-7637 7662);
FORCEPROP 1 LASTPIN (-7625 7850) $PN 2
R 1
J 0
(-7637 7812);
DISPLAY 0.489362 (-7637 7812);
PAINT MONO (-7637 7812);
FORCEPROP 1 LAST VALUE 4.7K
J 0
(-7600 7725);
DISPLAY 0.489362 (-7600 7725);
PAINT SKYBLUE (-7600 7725);
FORCEPROP 1 LAST MATERIAL CHIP
J 0
(-7600 7775);
DISPLAY 0.489362 (-7600 7775);
PAINT SKYBLUE (-7600 7775);
FORCEPROP 1 LAST PACK_TYPE 0402LF
R 1
J 0
(-7475 8000);
DISPLAY 0.978723 (-7475 8000);
PAINT SKYBLUE (-7475 8000);
DISPLAY INVISIBLE (-7475 8000);
FORCEPROP 1 LAST TOLERANCE 5%
R 1
J 0
(-7525 7750);
DISPLAY 0.978723 (-7525 7750);
PAINT SKYBLUE (-7525 7750);
DISPLAY INVISIBLE (-7525 7750);
FORCEPROP 1 LAST WATTAGE 1/16W
R 1
J 2
(-7475 7725);
DISPLAY 0.978723 (-7475 7725);
PAINT SKYBLUE (-7475 7725);
DISPLAY INVISIBLE (-7475 7725);
FORCEPROP 2 LAST CDS_LIB pure_quanta
J 0
(-7625 7750);
DISPLAY INVISIBLE (-7625 7750);
FORCEPROP 1 LAST PATH I41
R 1
J 0
(-7775 7700);
DISPLAY 0.978723 (-7775 7700);
PAINT WHITE (-7775 7700);
DISPLAY INVISIBLE (-7775 7700);
FORCEPROP 1 LAST PART_NUMBER CS24702JB10
R 1
J 0
(-7725 7700);
DISPLAY 0.978723 (-7725 7700);
PAINT SKYBLUE (-7725 7700);
DISPLAY INVISIBLE (-7725 7700);
FORCEADD Q_RES..1
R 1
(-7400 7750);
FORCEPROP 1 LAST LOCATION R288
J 0
(-7375 7675);
DISPLAY 0.489362 (-7375 7675);
PAINT SKYBLUE (-7375 7675);
FORCEPROP 2 LAST $SEC 1
J 0
(-7375 7800);
DISPLAY 0.680851 (-7375 7800);
PAINT MONO (-7375 7800);
DISPLAY INVISIBLE (-7375 7800);
FORCEPROP 2 LAST CDS_SEC 1
J 0
(-7375 7800);
DISPLAY 1.021277 (-7375 7800);
DISPLAY INVISIBLE (-7375 7800);
FORCEPROP 1 LASTPIN (-7400 7650) $PN 1
R 1
J 0
(-7412 7662);
DISPLAY 0.489362 (-7412 7662);
PAINT MONO (-7412 7662);
FORCEPROP 1 LASTPIN (-7400 7850) $PN 2
R 1
J 0
(-7412 7812);
DISPLAY 0.489362 (-7412 7812);
PAINT MONO (-7412 7812);
FORCEPROP 1 LAST MATERIAL EMPTY
J 0
(-7375 7775);
DISPLAY 0.489362 (-7375 7775);
PAINT RED (-7375 7775);
FORCEPROP 1 LAST VALUE 4.7K
J 0
(-7375 7725);
DISPLAY 0.489362 (-7375 7725);
PAINT SKYBLUE (-7375 7725);
FORCEPROP 1 LAST PACK_TYPE 0402LF
R 1
J 0
(-7250 8000);
DISPLAY 0.978723 (-7250 8000);
PAINT SKYBLUE (-7250 8000);
DISPLAY INVISIBLE (-7250 8000);
FORCEPROP 1 LAST TOLERANCE 5%
R 1
J 0
(-7300 7750);
DISPLAY 0.978723 (-7300 7750);
PAINT SKYBLUE (-7300 7750);
DISPLAY INVISIBLE (-7300 7750);
FORCEPROP 1 LAST WATTAGE 1/16W
R 1
J 2
(-7250 7725);
DISPLAY 0.978723 (-7250 7725);
PAINT SKYBLUE (-7250 7725);
DISPLAY INVISIBLE (-7250 7725);
FORCEPROP 2 LAST CDS_LIB pure_quanta
J 0
(-7400 7750);
DISPLAY INVISIBLE (-7400 7750);
FORCEPROP 1 LAST PATH I42
R 1
J 0
(-7550 7700);
DISPLAY 0.978723 (-7550 7700);
PAINT WHITE (-7550 7700);
DISPLAY INVISIBLE (-7550 7700);
FORCEPROP 1 LAST PART_NUMBER CS24702JB10
R 1
J 0
(-7500 7700);
DISPLAY 0.978723 (-7500 7700);
PAINT SKYBLUE (-7500 7700);
DISPLAY INVISIBLE (-7500 7700);
FORCEADD Q_RES..1
R 1
(-7225 7750);
FORCEPROP 1 LAST LOCATION R444
J 0
(-7200 7675);
DISPLAY 0.489362 (-7200 7675);
PAINT SKYBLUE (-7200 7675);
FORCEPROP 2 LAST $SEC 1
J 0
(-7200 7800);
DISPLAY 0.680851 (-7200 7800);
PAINT MONO (-7200 7800);
DISPLAY INVISIBLE (-7200 7800);
FORCEPROP 2 LAST CDS_SEC 1
J 0
(-7200 7800);
DISPLAY 1.021277 (-7200 7800);
DISPLAY INVISIBLE (-7200 7800);
FORCEPROP 1 LASTPIN (-7225 7650) $PN 1
R 1
J 0
(-7237 7662);
DISPLAY 0.489362 (-7237 7662);
PAINT MONO (-7237 7662);
FORCEPROP 1 LASTPIN (-7225 7850) $PN 2
R 1
J 0
(-7237 7812);
DISPLAY 0.489362 (-7237 7812);
PAINT MONO (-7237 7812);
FORCEPROP 1 LAST VALUE 4.7K
J 0
(-7200 7725);
DISPLAY 0.489362 (-7200 7725);
PAINT SKYBLUE (-7200 7725);
FORCEPROP 1 LAST MATERIAL CHIP
J 0
(-7200 7775);
DISPLAY 0.489362 (-7200 7775);
PAINT SKYBLUE (-7200 7775);
FORCEPROP 2 LAST CDS_LIB pure_quanta
J 0
(-7225 7750);
DISPLAY INVISIBLE (-7225 7750);
FORCEPROP 1 LAST WATTAGE 1/16W
R 1
J 2
(-7075 7725);
DISPLAY 0.978723 (-7075 7725);
PAINT SKYBLUE (-7075 7725);
DISPLAY INVISIBLE (-7075 7725);
FORCEPROP 1 LAST TOLERANCE 5%
R 1
J 0
(-7125 7750);
DISPLAY 0.978723 (-7125 7750);
PAINT SKYBLUE (-7125 7750);
DISPLAY INVISIBLE (-7125 7750);
FORCEPROP 1 LAST PACK_TYPE 0402LF
R 1
J 0
(-7075 8000);
DISPLAY 0.978723 (-7075 8000);
PAINT SKYBLUE (-7075 8000);
DISPLAY INVISIBLE (-7075 8000);
FORCEPROP 1 LAST PATH I43
R 1
J 0
(-7375 7700);
DISPLAY 0.978723 (-7375 7700);
PAINT WHITE (-7375 7700);
DISPLAY INVISIBLE (-7375 7700);
FORCEPROP 1 LAST PART_NUMBER CS24702JB10
R 1
J 0
(-7325 7700);
DISPLAY 0.978723 (-7325 7700);
PAINT SKYBLUE (-7325 7700);
DISPLAY INVISIBLE (-7325 7700);
FORCEADD Q_RES..1
(-7775 8175);
FORCEPROP 1 LAST LOCATION R207
J 0
(-7975 8175);
DISPLAY 0.489362 (-7975 8175);
PAINT SKYBLUE (-7975 8175);
FORCEPROP 0 LAST $SEC 1
J 0
(-7675 8200);
DISPLAY 0.680851 (-7675 8200);
PAINT MONO (-7675 8200);
DISPLAY INVISIBLE (-7675 8200);
FORCEPROP 0 LAST CDS_SEC 1
J 0
(-7675 8200);
DISPLAY 0.680851 (-7675 8200);
DISPLAY INVISIBLE (-7675 8200);
FORCEPROP 1 LASTPIN (-7875 8175) $PN 1
J 0
(-7863 8187);
DISPLAY 0.489362 (-7863 8187);
PAINT MONO (-7863 8187);
FORCEPROP 1 LASTPIN (-7675 8175) $PN 2
J 0
(-7713 8187);
DISPLAY 0.489362 (-7713 8187);
PAINT MONO (-7713 8187);
FORCEPROP 1 LAST VALUE 2.2K
J 0
(-7675 8175);
DISPLAY 0.489362 (-7675 8175);
PAINT SKYBLUE (-7675 8175);
FORCEPROP 2 LAST CDS_LIB pure_quanta
J 0
(-7775 8175);
DISPLAY INVISIBLE (-7775 8175);
FORCEPROP 1 LAST WATTAGE 1/16W
J 2
(-7800 8025);
DISPLAY 0.978723 (-7800 8025);
PAINT SKYBLUE (-7800 8025);
DISPLAY INVISIBLE (-7800 8025);
FORCEPROP 1 LAST MATERIAL CHIP
J 0
(-7775 8025);
DISPLAY 0.978723 (-7775 8025);
PAINT SKYBLUE (-7775 8025);
DISPLAY INVISIBLE (-7775 8025);
FORCEPROP 1 LAST TOLERANCE 5%
J 0
(-7775 8075);
DISPLAY 0.978723 (-7775 8075);
PAINT SKYBLUE (-7775 8075);
DISPLAY INVISIBLE (-7775 8075);
FORCEPROP 1 LAST PACK_TYPE 0402LF
J 0
(-7525 8025);
DISPLAY 0.978723 (-7525 8025);
PAINT SKYBLUE (-7525 8025);
DISPLAY INVISIBLE (-7525 8025);
FORCEPROP 1 LAST PATH I44
J 0
(-7825 8325);
DISPLAY 0.978723 (-7825 8325);
PAINT WHITE (-7825 8325);
DISPLAY INVISIBLE (-7825 8325);
FORCEPROP 1 LAST PART_NUMBER CS22202JB07
J 0
(-7825 8275);
DISPLAY 0.978723 (-7825 8275);
PAINT SKYBLUE (-7825 8275);
DISPLAY INVISIBLE (-7825 8275);
FORCEADD Q_RES..1
(-7775 8225);
FORCEPROP 1 LAST LOCATION R452
J 0
(-7975 8225);
DISPLAY 0.489362 (-7975 8225);
PAINT SKYBLUE (-7975 8225);
FORCEPROP 0 LAST $SEC 1
J 0
(-7950 8275);
DISPLAY 0.680851 (-7950 8275);
PAINT MONO (-7950 8275);
DISPLAY INVISIBLE (-7950 8275);
FORCEPROP 0 LAST CDS_SEC 1
J 0
(-7950 8275);
DISPLAY 1.021277 (-7950 8275);
DISPLAY INVISIBLE (-7950 8275);
FORCEPROP 1 LASTPIN (-7875 8225) $PN 1
J 0
(-7863 8237);
DISPLAY 0.489362 (-7863 8237);
PAINT MONO (-7863 8237);
FORCEPROP 1 LASTPIN (-7675 8225) $PN 2
J 0
(-7713 8237);
DISPLAY 0.489362 (-7713 8237);
PAINT MONO (-7713 8237);
FORCEPROP 1 LAST VALUE 4.7K
J 0
(-7675 8225);
DISPLAY 0.489362 (-7675 8225);
PAINT SKYBLUE (-7675 8225);
FORCEPROP 1 LAST PACK_TYPE 0402LF
J 0
(-7525 8075);
DISPLAY 0.510638 (-7525 8075);
PAINT SKYBLUE (-7525 8075);
DISPLAY INVISIBLE (-7525 8075);
FORCEPROP 1 LAST TOLERANCE 5%
J 0
(-7650 8225);
DISPLAY 0.510638 (-7650 8225);
PAINT SKYBLUE (-7650 8225);
DISPLAY INVISIBLE (-7650 8225);
FORCEPROP 1 LAST MATERIAL CHIP
J 0
(-7675 8200);
DISPLAY 0.489362 (-7675 8200);
PAINT SKYBLUE (-7675 8200);
DISPLAY INVISIBLE (-7675 8200);
FORCEPROP 1 LAST WATTAGE 1/16W
J 2
(-7800 8075);
DISPLAY 0.510638 (-7800 8075);
PAINT SKYBLUE (-7800 8075);
DISPLAY INVISIBLE (-7800 8075);
FORCEPROP 2 LAST CDS_LIB pure_quanta
J 0
(-7775 8225);
DISPLAY INVISIBLE (-7775 8225);
FORCEPROP 1 LAST PATH I45
J 0
(-7825 8375);
DISPLAY 0.978723 (-7825 8375);
PAINT WHITE (-7825 8375);
DISPLAY INVISIBLE (-7825 8375);
FORCEPROP 1 LAST PART_NUMBER CS24702JB10
J 0
(-7825 8325);
DISPLAY 0.510638 (-7825 8325);
PAINT SKYBLUE (-7825 8325);
DISPLAY INVISIBLE (-7825 8325);
FORCEADD Q_RES..1
(-7775 8275);
FORCEPROP 1 LAST LOCATION R451
J 0
(-7975 8275);
DISPLAY 0.489362 (-7975 8275);
PAINT SKYBLUE (-7975 8275);
FORCEPROP 0 LAST $SEC 1
J 0
(-7950 8325);
DISPLAY 0.680851 (-7950 8325);
PAINT MONO (-7950 8325);
DISPLAY INVISIBLE (-7950 8325);
FORCEPROP 0 LAST CDS_SEC 1
J 0
(-7950 8325);
DISPLAY 1.021277 (-7950 8325);
DISPLAY INVISIBLE (-7950 8325);
FORCEPROP 1 LASTPIN (-7875 8275) $PN 1
J 0
(-7863 8287);
DISPLAY 0.489362 (-7863 8287);
PAINT MONO (-7863 8287);
FORCEPROP 1 LASTPIN (-7675 8275) $PN 2
J 0
(-7713 8287);
DISPLAY 0.489362 (-7713 8287);
PAINT MONO (-7713 8287);
FORCEPROP 1 LAST VALUE 4.7K
J 0
(-7675 8275);
DISPLAY 0.489362 (-7675 8275);
PAINT SKYBLUE (-7675 8275);
FORCEPROP 1 LAST PACK_TYPE 0402LF
J 0
(-7525 8125);
DISPLAY 0.510638 (-7525 8125);
PAINT SKYBLUE (-7525 8125);
DISPLAY INVISIBLE (-7525 8125);
FORCEPROP 1 LAST TOLERANCE 5%
J 0
(-7650 8275);
DISPLAY 0.510638 (-7650 8275);
PAINT SKYBLUE (-7650 8275);
DISPLAY INVISIBLE (-7650 8275);
FORCEPROP 1 LAST MATERIAL CHIP
J 0
(-7675 8250);
DISPLAY 0.489362 (-7675 8250);
PAINT SKYBLUE (-7675 8250);
DISPLAY INVISIBLE (-7675 8250);
FORCEPROP 1 LAST WATTAGE 1/16W
J 2
(-7800 8125);
DISPLAY 0.510638 (-7800 8125);
PAINT SKYBLUE (-7800 8125);
DISPLAY INVISIBLE (-7800 8125);
FORCEPROP 2 LAST CDS_LIB pure_quanta
J 0
(-7775 8275);
DISPLAY INVISIBLE (-7775 8275);
FORCEPROP 1 LAST PATH I46
J 0
(-7825 8425);
DISPLAY 0.978723 (-7825 8425);
PAINT WHITE (-7825 8425);
DISPLAY INVISIBLE (-7825 8425);
FORCEPROP 1 LAST PART_NUMBER CS24702JB10
J 0
(-7825 8375);
DISPLAY 0.510638 (-7825 8375);
PAINT SKYBLUE (-7825 8375);
DISPLAY INVISIBLE (-7825 8375);
FORCEADD Q_RES..1
(-7775 8325);
FORCEPROP 1 LAST LOCATION R450
J 0
(-7975 8325);
DISPLAY 0.489362 (-7975 8325);
PAINT SKYBLUE (-7975 8325);
FORCEPROP 0 LAST $SEC 1
J 0
(-7950 8375);
DISPLAY 0.680851 (-7950 8375);
PAINT MONO (-7950 8375);
DISPLAY INVISIBLE (-7950 8375);
FORCEPROP 0 LAST CDS_SEC 1
J 0
(-7950 8375);
DISPLAY 1.021277 (-7950 8375);
DISPLAY INVISIBLE (-7950 8375);
FORCEPROP 1 LASTPIN (-7875 8325) $PN 1
J 0
(-7863 8337);
DISPLAY 0.489362 (-7863 8337);
PAINT MONO (-7863 8337);
FORCEPROP 1 LASTPIN (-7675 8325) $PN 2
J 0
(-7713 8337);
DISPLAY 0.489362 (-7713 8337);
PAINT MONO (-7713 8337);
FORCEPROP 1 LAST VALUE 4.7K
J 0
(-7675 8325);
DISPLAY 0.489362 (-7675 8325);
PAINT SKYBLUE (-7675 8325);
FORCEPROP 1 LAST PACK_TYPE 0402LF
J 0
(-7525 8175);
DISPLAY 0.510638 (-7525 8175);
PAINT SKYBLUE (-7525 8175);
DISPLAY INVISIBLE (-7525 8175);
FORCEPROP 1 LAST TOLERANCE 5%
J 0
(-7650 8325);
DISPLAY 0.510638 (-7650 8325);
PAINT SKYBLUE (-7650 8325);
DISPLAY INVISIBLE (-7650 8325);
FORCEPROP 1 LAST MATERIAL CHIP
J 0
(-7675 8300);
DISPLAY 0.489362 (-7675 8300);
PAINT SKYBLUE (-7675 8300);
DISPLAY INVISIBLE (-7675 8300);
FORCEPROP 1 LAST WATTAGE 1/16W
J 2
(-7800 8175);
DISPLAY 0.510638 (-7800 8175);
PAINT SKYBLUE (-7800 8175);
DISPLAY INVISIBLE (-7800 8175);
FORCEPROP 2 LAST CDS_LIB pure_quanta
J 0
(-7775 8325);
DISPLAY INVISIBLE (-7775 8325);
FORCEPROP 1 LAST PATH I47
J 0
(-7825 8475);
DISPLAY 0.978723 (-7825 8475);
PAINT WHITE (-7825 8475);
DISPLAY INVISIBLE (-7825 8475);
FORCEPROP 1 LAST PART_NUMBER CS24702JB10
J 0
(-7825 8425);
DISPLAY 0.510638 (-7825 8425);
PAINT SKYBLUE (-7825 8425);
DISPLAY INVISIBLE (-7825 8425);
FORCEADD Q_RES..1
(-7775 8375);
FORCEPROP 1 LAST LOCATION R449
J 0
(-7975 8375);
DISPLAY 0.489362 (-7975 8375);
PAINT SKYBLUE (-7975 8375);
FORCEPROP 0 LAST $SEC 1
J 0
(-7950 8425);
DISPLAY 0.680851 (-7950 8425);
PAINT MONO (-7950 8425);
DISPLAY INVISIBLE (-7950 8425);
FORCEPROP 0 LAST CDS_SEC 1
J 0
(-7950 8425);
DISPLAY 1.021277 (-7950 8425);
DISPLAY INVISIBLE (-7950 8425);
FORCEPROP 1 LASTPIN (-7875 8375) $PN 1
J 0
(-7863 8387);
DISPLAY 0.489362 (-7863 8387);
PAINT MONO (-7863 8387);
FORCEPROP 1 LASTPIN (-7675 8375) $PN 2
J 0
(-7713 8387);
DISPLAY 0.489362 (-7713 8387);
PAINT MONO (-7713 8387);
FORCEPROP 1 LAST VALUE 4.7K
J 0
(-7675 8375);
DISPLAY 0.489362 (-7675 8375);
PAINT SKYBLUE (-7675 8375);
FORCEPROP 1 LAST MATERIAL EMPTY
J 0
(-8100 8375);
DISPLAY 0.489362 (-8100 8375);
PAINT RED (-8100 8375);
FORCEPROP 1 LAST PACK_TYPE 0402LF
J 0
(-7525 8225);
DISPLAY 0.510638 (-7525 8225);
PAINT SKYBLUE (-7525 8225);
DISPLAY INVISIBLE (-7525 8225);
FORCEPROP 1 LAST TOLERANCE 5%
J 0
(-7650 8375);
DISPLAY 0.510638 (-7650 8375);
PAINT SKYBLUE (-7650 8375);
DISPLAY INVISIBLE (-7650 8375);
FORCEPROP 1 LAST WATTAGE 1/16W
J 2
(-7800 8225);
DISPLAY 0.510638 (-7800 8225);
PAINT SKYBLUE (-7800 8225);
DISPLAY INVISIBLE (-7800 8225);
FORCEPROP 2 LAST CDS_LIB pure_quanta
J 0
(-7775 8375);
DISPLAY INVISIBLE (-7775 8375);
FORCEPROP 1 LAST PATH I48
J 0
(-7825 8525);
DISPLAY 0.978723 (-7825 8525);
PAINT WHITE (-7825 8525);
DISPLAY INVISIBLE (-7825 8525);
FORCEPROP 1 LAST PART_NUMBER CS24702JB10
J 0
(-7825 8475);
DISPLAY 0.510638 (-7825 8475);
PAINT SKYBLUE (-7825 8475);
DISPLAY INVISIBLE (-7825 8475);
FORCEADD Q_RES..1
(-7775 8425);
FORCEPROP 1 LAST LOCATION R448
J 0
(-7975 8425);
DISPLAY 0.489362 (-7975 8425);
PAINT SKYBLUE (-7975 8425);
FORCEPROP 0 LAST $SEC 1
J 0
(-7950 8475);
DISPLAY 0.680851 (-7950 8475);
PAINT MONO (-7950 8475);
DISPLAY INVISIBLE (-7950 8475);
FORCEPROP 0 LAST CDS_SEC 1
J 0
(-7950 8475);
DISPLAY 1.021277 (-7950 8475);
DISPLAY INVISIBLE (-7950 8475);
FORCEPROP 1 LASTPIN (-7875 8425) $PN 1
J 0
(-7863 8437);
DISPLAY 0.489362 (-7863 8437);
PAINT MONO (-7863 8437);
FORCEPROP 1 LASTPIN (-7675 8425) $PN 2
J 0
(-7713 8437);
DISPLAY 0.489362 (-7713 8437);
PAINT MONO (-7713 8437);
FORCEPROP 1 LAST VALUE 4.7K
J 0
(-7675 8425);
DISPLAY 0.489362 (-7675 8425);
PAINT SKYBLUE (-7675 8425);
FORCEPROP 1 LAST MATERIAL EMPTY
J 0
(-8100 8425);
DISPLAY 0.489362 (-8100 8425);
PAINT RED (-8100 8425);
FORCEPROP 1 LAST PACK_TYPE 0402LF
J 0
(-7525 8275);
DISPLAY 0.510638 (-7525 8275);
PAINT SKYBLUE (-7525 8275);
DISPLAY INVISIBLE (-7525 8275);
FORCEPROP 1 LAST TOLERANCE 5%
J 0
(-7650 8425);
DISPLAY 0.510638 (-7650 8425);
PAINT SKYBLUE (-7650 8425);
DISPLAY INVISIBLE (-7650 8425);
FORCEPROP 1 LAST WATTAGE 1/16W
J 2
(-7800 8275);
DISPLAY 0.510638 (-7800 8275);
PAINT SKYBLUE (-7800 8275);
DISPLAY INVISIBLE (-7800 8275);
FORCEPROP 2 LAST CDS_LIB pure_quanta
J 0
(-7775 8425);
DISPLAY INVISIBLE (-7775 8425);
FORCEPROP 1 LAST PATH I49
J 0
(-7825 8575);
DISPLAY 0.978723 (-7825 8575);
PAINT WHITE (-7825 8575);
DISPLAY INVISIBLE (-7825 8575);
FORCEPROP 1 LAST PART_NUMBER CS24702JB10
J 0
(-7825 8525);
DISPLAY 0.510638 (-7825 8525);
PAINT SKYBLUE (-7825 8525);
DISPLAY INVISIBLE (-7825 8525);
FORCEADD OFFPAGE..2
R 2
(-8775 7550);
FORCEPROP 2 LAST $XR0 28 
J 0
(-8999 7550);
DISPLAY 0.638298 (-8999 7550);
PAINT MONO (-8999 7550);
FORCEPROP 2 LAST CDS_LIB standard
J 0
(-8775 7550);
DISPLAY INVISIBLE (-8775 7550);
FORCEPROP 1 LAST OFFPAGE TRUE
J 2
(-9100 7425);
DISPLAY 0.872340 (-9100 7425);
PAINT GREEN (-9100 7425);
DISPLAY INVISIBLE (-9100 7425);
FORCEPROP 1 LAST COMMENT_BODY TRUE
J 2
(-8730 7455);
DISPLAY 0.872340 (-8730 7455);
PAINT GREEN (-8730 7455);
DISPLAY INVISIBLE (-8730 7455);
FORCEPROP 2 LAST PATH I5
J 0
(-8975 7600);
DISPLAY 0.680851 (-8975 7600);
DISPLAY INVISIBLE (-8975 7600);
FORCEADD Q_RES..1
(-7775 8675);
FORCEPROP 1 LAST LOCATION R443
J 0
(-7975 8675);
DISPLAY 0.489362 (-7975 8675);
PAINT SKYBLUE (-7975 8675);
FORCEPROP 0 LAST $SEC 1
J 0
(-7675 8700);
DISPLAY 0.680851 (-7675 8700);
PAINT MONO (-7675 8700);
DISPLAY INVISIBLE (-7675 8700);
FORCEPROP 0 LAST CDS_SEC 1
J 0
(-7675 8700);
DISPLAY 0.680851 (-7675 8700);
DISPLAY INVISIBLE (-7675 8700);
FORCEPROP 1 LASTPIN (-7875 8675) $PN 1
J 0
(-7863 8687);
DISPLAY 0.489362 (-7863 8687);
PAINT MONO (-7863 8687);
FORCEPROP 1 LASTPIN (-7675 8675) $PN 2
J 0
(-7713 8687);
DISPLAY 0.489362 (-7713 8687);
PAINT MONO (-7713 8687);
FORCEPROP 1 LAST VALUE 1K
J 0
(-7675 8675);
DISPLAY 0.489362 (-7675 8675);
PAINT SKYBLUE (-7675 8675);
FORCEPROP 1 LAST TOLERANCE 1%
J 0
(-7775 8575);
DISPLAY 0.978723 (-7775 8575);
PAINT SKYBLUE (-7775 8575);
DISPLAY INVISIBLE (-7775 8575);
FORCEPROP 1 LAST PACK_TYPE 0402LF
J 0
(-7525 8525);
DISPLAY 0.978723 (-7525 8525);
PAINT SKYBLUE (-7525 8525);
DISPLAY INVISIBLE (-7525 8525);
FORCEPROP 1 LAST MATERIAL CHIP
J 0
(-7775 8525);
DISPLAY 0.978723 (-7775 8525);
PAINT SKYBLUE (-7775 8525);
DISPLAY INVISIBLE (-7775 8525);
FORCEPROP 1 LAST WATTAGE 1/16W
J 2
(-7800 8525);
DISPLAY 0.978723 (-7800 8525);
PAINT SKYBLUE (-7800 8525);
DISPLAY INVISIBLE (-7800 8525);
FORCEPROP 2 LAST CDS_LIB pure_quanta
J 0
(-7775 8675);
DISPLAY INVISIBLE (-7775 8675);
FORCEPROP 1 LAST PATH I53
J 0
(-7825 8825);
DISPLAY 0.978723 (-7825 8825);
PAINT WHITE (-7825 8825);
DISPLAY INVISIBLE (-7825 8825);
FORCEPROP 1 LAST PART_NUMBER CS21002FB06
J 0
(-7825 8775);
DISPLAY 0.978723 (-7825 8775);
PAINT SKYBLUE (-7825 8775);
DISPLAY INVISIBLE (-7825 8775);
FORCEADD Q_RES..1
(-7775 8775);
FORCEPROP 1 LAST LOCATION R441
J 0
(-7975 8775);
DISPLAY 0.489362 (-7975 8775);
PAINT SKYBLUE (-7975 8775);
FORCEPROP 0 LAST $SEC 1
J 0
(-7675 8800);
DISPLAY 0.680851 (-7675 8800);
PAINT MONO (-7675 8800);
DISPLAY INVISIBLE (-7675 8800);
FORCEPROP 0 LAST CDS_SEC 1
J 0
(-7675 8800);
DISPLAY 0.680851 (-7675 8800);
DISPLAY INVISIBLE (-7675 8800);
FORCEPROP 1 LASTPIN (-7875 8775) $PN 1
J 0
(-7863 8787);
DISPLAY 0.489362 (-7863 8787);
PAINT MONO (-7863 8787);
FORCEPROP 1 LASTPIN (-7675 8775) $PN 2
J 0
(-7713 8787);
DISPLAY 0.489362 (-7713 8787);
PAINT MONO (-7713 8787);
FORCEPROP 1 LAST VALUE 2.2K
J 0
(-7675 8775);
DISPLAY 0.489362 (-7675 8775);
PAINT SKYBLUE (-7675 8775);
FORCEPROP 2 LAST CDS_LIB pure_quanta
J 0
(-7775 8775);
DISPLAY INVISIBLE (-7775 8775);
FORCEPROP 1 LAST WATTAGE 1/16W
J 2
(-7800 8625);
DISPLAY 0.978723 (-7800 8625);
PAINT SKYBLUE (-7800 8625);
DISPLAY INVISIBLE (-7800 8625);
FORCEPROP 1 LAST MATERIAL CHIP
J 0
(-7775 8625);
DISPLAY 0.978723 (-7775 8625);
PAINT SKYBLUE (-7775 8625);
DISPLAY INVISIBLE (-7775 8625);
FORCEPROP 1 LAST TOLERANCE 5%
J 0
(-7775 8675);
DISPLAY 0.978723 (-7775 8675);
PAINT SKYBLUE (-7775 8675);
DISPLAY INVISIBLE (-7775 8675);
FORCEPROP 1 LAST PACK_TYPE 0402LF
J 0
(-7525 8625);
DISPLAY 0.978723 (-7525 8625);
PAINT SKYBLUE (-7525 8625);
DISPLAY INVISIBLE (-7525 8625);
FORCEPROP 1 LAST PATH I55
J 0
(-7825 8925);
DISPLAY 0.978723 (-7825 8925);
PAINT WHITE (-7825 8925);
DISPLAY INVISIBLE (-7825 8925);
FORCEPROP 1 LAST PART_NUMBER CS22202JB07
J 0
(-7825 8875);
DISPLAY 0.978723 (-7825 8875);
PAINT SKYBLUE (-7825 8875);
DISPLAY INVISIBLE (-7825 8875);
FORCEADD Q_RES..1
(-7775 8725);
FORCEPROP 1 LAST LOCATION R442
J 0
(-7975 8725);
DISPLAY 0.489362 (-7975 8725);
PAINT SKYBLUE (-7975 8725);
FORCEPROP 0 LAST $SEC 1
J 0
(-7675 8750);
DISPLAY 0.680851 (-7675 8750);
PAINT MONO (-7675 8750);
DISPLAY INVISIBLE (-7675 8750);
FORCEPROP 0 LAST CDS_SEC 1
J 0
(-7675 8750);
DISPLAY 0.680851 (-7675 8750);
DISPLAY INVISIBLE (-7675 8750);
FORCEPROP 1 LASTPIN (-7875 8725) $PN 1
J 0
(-7863 8737);
DISPLAY 0.489362 (-7863 8737);
PAINT MONO (-7863 8737);
FORCEPROP 1 LASTPIN (-7675 8725) $PN 2
J 0
(-7713 8737);
DISPLAY 0.489362 (-7713 8737);
PAINT MONO (-7713 8737);
FORCEPROP 1 LAST VALUE 1K
J 0
(-7675 8725);
DISPLAY 0.489362 (-7675 8725);
PAINT SKYBLUE (-7675 8725);
FORCEPROP 1 LAST TOLERANCE 1%
J 0
(-7775 8625);
DISPLAY 0.978723 (-7775 8625);
PAINT SKYBLUE (-7775 8625);
DISPLAY INVISIBLE (-7775 8625);
FORCEPROP 1 LAST PACK_TYPE 0402LF
J 0
(-7525 8575);
DISPLAY 0.978723 (-7525 8575);
PAINT SKYBLUE (-7525 8575);
DISPLAY INVISIBLE (-7525 8575);
FORCEPROP 1 LAST MATERIAL CHIP
J 0
(-7775 8575);
DISPLAY 0.978723 (-7775 8575);
PAINT SKYBLUE (-7775 8575);
DISPLAY INVISIBLE (-7775 8575);
FORCEPROP 1 LAST WATTAGE 1/16W
J 2
(-7800 8575);
DISPLAY 0.978723 (-7800 8575);
PAINT SKYBLUE (-7800 8575);
DISPLAY INVISIBLE (-7800 8575);
FORCEPROP 2 LAST CDS_LIB pure_quanta
J 0
(-7775 8725);
DISPLAY INVISIBLE (-7775 8725);
FORCEPROP 1 LAST PATH I56
J 0
(-7825 8875);
DISPLAY 0.978723 (-7825 8875);
PAINT WHITE (-7825 8875);
DISPLAY INVISIBLE (-7825 8875);
FORCEPROP 1 LAST PART_NUMBER CS21002FB06
J 0
(-7825 8825);
DISPLAY 0.978723 (-7825 8825);
PAINT SKYBLUE (-7825 8825);
DISPLAY INVISIBLE (-7825 8825);
FORCEADD UNIVERSAL_POWER..1
(-7400 8000);
FORCEPROP 3 LASTPIN (-7400 7950) SIG_NAME PVDD18_S5_P0\g
J 0
(-7390 7960);
DISPLAY 0.659574 (-7390 7960);
PAINT MONO (-7390 7960);
DISPLAY INVISIBLE (-7390 7960);
FORCEPROP 1 LAST HDL_POWER PVDD18_S5_P0
J 1
(-7400 8050);
DISPLAY 0.489362 (-7400 8050);
PAINT GREEN (-7400 8050);
FORCEPROP 2 LAST CDS_LIB pure_quanta_power
J 0
(-7400 8000);
DISPLAY INVISIBLE (-7400 8000);
FORCEPROP 1 LAST PATH I57
J 0
(-7350 8025);
DISPLAY 0.872340 (-7350 8025);
PAINT AQUA (-7350 8025);
DISPLAY INVISIBLE (-7350 8025);
FORCEADD UNIVERSAL_GND..1
(-7075 7075);
FORCEPROP 3 LASTPIN (-7075 7125) SIG_NAME GND\g
J 0
(-7065 7135);
DISPLAY 0.659574 (-7065 7135);
PAINT MONO (-7065 7135);
DISPLAY INVISIBLE (-7065 7135);
FORCEPROP 2 LAST CDS_LIB pure_quanta_power
J 0
(-7075 7075);
DISPLAY INVISIBLE (-7075 7075);
FORCEPROP 1 LAST HDL_POWER GND
J 1
(-7050 7000);
DISPLAY 0.872340 (-7050 7000);
PAINT GREEN (-7050 7000);
DISPLAY INVISIBLE (-7050 7000);
FORCEPROP 1 LAST PATH I58
J 0
(-7000 7075);
DISPLAY 0.872340 (-7000 7075);
PAINT AQUA (-7000 7075);
DISPLAY INVISIBLE (-7000 7075);
FORCEADD Q_RES..1
R 1
(-7075 7225);
FORCEPROP 1 LAST LOCATION R5027
J 0
(-7050 7150);
DISPLAY 0.489362 (-7050 7150);
PAINT SKYBLUE (-7050 7150);
FORCEPROP 2 LAST $SEC 1
J 0
(-7050 7275);
DISPLAY 0.680851 (-7050 7275);
PAINT MONO (-7050 7275);
DISPLAY INVISIBLE (-7050 7275);
FORCEPROP 2 LAST CDS_SEC 1
J 0
(-7050 7275);
DISPLAY 1.021277 (-7050 7275);
DISPLAY INVISIBLE (-7050 7275);
FORCEPROP 1 LASTPIN (-7075 7125) $PN 1
R 1
J 0
(-7087 7137);
DISPLAY 0.489362 (-7087 7137);
PAINT MONO (-7087 7137);
FORCEPROP 1 LASTPIN (-7075 7325) $PN 2
R 1
J 0
(-7087 7287);
DISPLAY 0.489362 (-7087 7287);
PAINT MONO (-7087 7287);
FORCEPROP 1 LAST VALUE 4.7K
J 0
(-7050 7200);
DISPLAY 0.489362 (-7050 7200);
PAINT SKYBLUE (-7050 7200);
FORCEPROP 1 LAST MATERIAL EMPTY
J 0
(-7050 7250);
DISPLAY 0.489362 (-7050 7250);
PAINT RED (-7050 7250);
FORCEPROP 2 LAST CDS_LIB pure_quanta
J 0
(-7075 7225);
DISPLAY INVISIBLE (-7075 7225);
FORCEPROP 1 LAST WATTAGE 1/16W
R 1
J 2
(-6925 7200);
DISPLAY 0.978723 (-6925 7200);
PAINT SKYBLUE (-6925 7200);
DISPLAY INVISIBLE (-6925 7200);
FORCEPROP 1 LAST TOLERANCE 5%
R 1
J 0
(-6975 7225);
DISPLAY 0.978723 (-6975 7225);
PAINT SKYBLUE (-6975 7225);
DISPLAY INVISIBLE (-6975 7225);
FORCEPROP 1 LAST PACK_TYPE 0402LF
R 1
J 0
(-6925 7475);
DISPLAY 0.978723 (-6925 7475);
PAINT SKYBLUE (-6925 7475);
DISPLAY INVISIBLE (-6925 7475);
FORCEPROP 1 LAST PATH I59
R 1
J 0
(-7225 7175);
DISPLAY 0.978723 (-7225 7175);
PAINT WHITE (-7225 7175);
DISPLAY INVISIBLE (-7225 7175);
FORCEPROP 1 LAST PART_NUMBER CS24702JB10
R 1
J 0
(-7175 7175);
DISPLAY 0.978723 (-7175 7175);
PAINT SKYBLUE (-7175 7175);
DISPLAY INVISIBLE (-7175 7175);
FORCEADD OFFPAGE..2
R 2
(-8775 7600);
FORCEPROP 2 LAST $XR1 28 
J 0
(-9089 7600);
DISPLAY 0.638298 (-9089 7600);
PAINT MONO (-9089 7600);
FORCEPROP 2 LAST $XR0 81 
J 0
(-8999 7600);
DISPLAY 0.638298 (-8999 7600);
PAINT MONO (-8999 7600);
FORCEPROP 2 LAST CDS_LIB standard
J 0
(-8775 7600);
DISPLAY INVISIBLE (-8775 7600);
FORCEPROP 1 LAST OFFPAGE TRUE
J 2
(-9100 7475);
DISPLAY 0.872340 (-9100 7475);
PAINT GREEN (-9100 7475);
DISPLAY INVISIBLE (-9100 7475);
FORCEPROP 1 LAST COMMENT_BODY TRUE
J 2
(-8730 7505);
DISPLAY 0.872340 (-8730 7505);
PAINT GREEN (-8730 7505);
DISPLAY INVISIBLE (-8730 7505);
FORCEPROP 2 LAST PATH I6
J 0
(-8975 7650);
DISPLAY 0.680851 (-8975 7650);
DISPLAY INVISIBLE (-8975 7650);
FORCEADD Q_RES..1
R 1
(-6925 7225);
FORCEPROP 1 LAST LOCATION R5028
J 0
(-6900 7150);
DISPLAY 0.489362 (-6900 7150);
PAINT SKYBLUE (-6900 7150);
FORCEPROP 2 LAST $SEC 1
J 0
(-6900 7275);
DISPLAY 0.680851 (-6900 7275);
PAINT MONO (-6900 7275);
DISPLAY INVISIBLE (-6900 7275);
FORCEPROP 2 LAST CDS_SEC 1
J 0
(-6900 7275);
DISPLAY 1.021277 (-6900 7275);
DISPLAY INVISIBLE (-6900 7275);
FORCEPROP 1 LASTPIN (-6925 7125) $PN 1
R 1
J 0
(-6937 7137);
DISPLAY 0.489362 (-6937 7137);
PAINT MONO (-6937 7137);
FORCEPROP 1 LASTPIN (-6925 7325) $PN 2
R 1
J 0
(-6937 7287);
DISPLAY 0.489362 (-6937 7287);
PAINT MONO (-6937 7287);
FORCEPROP 1 LAST VALUE 4.7K
J 0
(-6900 7200);
DISPLAY 0.489362 (-6900 7200);
PAINT SKYBLUE (-6900 7200);
FORCEPROP 1 LAST MATERIAL EMPTY
J 0
(-6900 7250);
DISPLAY 0.489362 (-6900 7250);
PAINT RED (-6900 7250);
FORCEPROP 2 LAST CDS_LIB pure_quanta
J 0
(-6925 7225);
DISPLAY INVISIBLE (-6925 7225);
FORCEPROP 1 LAST WATTAGE 1/16W
R 1
J 2
(-6775 7200);
DISPLAY 0.978723 (-6775 7200);
PAINT SKYBLUE (-6775 7200);
DISPLAY INVISIBLE (-6775 7200);
FORCEPROP 1 LAST TOLERANCE 5%
R 1
J 0
(-6825 7225);
DISPLAY 0.978723 (-6825 7225);
PAINT SKYBLUE (-6825 7225);
DISPLAY INVISIBLE (-6825 7225);
FORCEPROP 1 LAST PACK_TYPE 0402LF
R 1
J 0
(-6775 7475);
DISPLAY 0.978723 (-6775 7475);
PAINT SKYBLUE (-6775 7475);
DISPLAY INVISIBLE (-6775 7475);
FORCEPROP 1 LAST PATH I60
R 1
J 0
(-7075 7175);
DISPLAY 0.978723 (-7075 7175);
PAINT WHITE (-7075 7175);
DISPLAY INVISIBLE (-7075 7175);
FORCEPROP 1 LAST PART_NUMBER CS24702JB10
R 1
J 0
(-7025 7175);
DISPLAY 0.978723 (-7025 7175);
PAINT SKYBLUE (-7025 7175);
DISPLAY INVISIBLE (-7025 7175);
FORCEADD UNIVERSAL_GND..1
(-6925 7075);
FORCEPROP 3 LASTPIN (-6925 7125) SIG_NAME GND\g
J 0
(-6915 7135);
DISPLAY 0.659574 (-6915 7135);
PAINT MONO (-6915 7135);
DISPLAY INVISIBLE (-6915 7135);
FORCEPROP 2 LAST CDS_LIB pure_quanta_power
J 0
(-6925 7075);
DISPLAY INVISIBLE (-6925 7075);
FORCEPROP 1 LAST HDL_POWER GND
J 1
(-6900 7000);
DISPLAY 0.872340 (-6900 7000);
PAINT GREEN (-6900 7000);
DISPLAY INVISIBLE (-6900 7000);
FORCEPROP 1 LAST PATH I61
J 0
(-6850 7075);
DISPLAY 0.872340 (-6850 7075);
PAINT AQUA (-6850 7075);
DISPLAY INVISIBLE (-6850 7075);
FORCEADD Q_RES..1
R 1
(-6775 7225);
FORCEPROP 1 LAST LOCATION R5029
J 0
(-6750 7150);
DISPLAY 0.489362 (-6750 7150);
PAINT SKYBLUE (-6750 7150);
FORCEPROP 2 LAST $SEC 1
J 0
(-6750 7275);
DISPLAY 0.680851 (-6750 7275);
PAINT MONO (-6750 7275);
DISPLAY INVISIBLE (-6750 7275);
FORCEPROP 2 LAST CDS_SEC 1
J 0
(-6750 7275);
DISPLAY 1.021277 (-6750 7275);
DISPLAY INVISIBLE (-6750 7275);
FORCEPROP 1 LASTPIN (-6775 7125) $PN 1
R 1
J 0
(-6787 7137);
DISPLAY 0.489362 (-6787 7137);
PAINT MONO (-6787 7137);
FORCEPROP 1 LASTPIN (-6775 7325) $PN 2
R 1
J 0
(-6787 7287);
DISPLAY 0.489362 (-6787 7287);
PAINT MONO (-6787 7287);
FORCEPROP 1 LAST VALUE 4.7K
J 0
(-6750 7200);
DISPLAY 0.489362 (-6750 7200);
PAINT SKYBLUE (-6750 7200);
FORCEPROP 1 LAST MATERIAL EMPTY
J 0
(-6750 7250);
DISPLAY 0.489362 (-6750 7250);
PAINT RED (-6750 7250);
FORCEPROP 2 LAST CDS_LIB pure_quanta
J 0
(-6775 7225);
DISPLAY INVISIBLE (-6775 7225);
FORCEPROP 1 LAST WATTAGE 1/16W
R 1
J 2
(-6625 7200);
DISPLAY 0.978723 (-6625 7200);
PAINT SKYBLUE (-6625 7200);
DISPLAY INVISIBLE (-6625 7200);
FORCEPROP 1 LAST TOLERANCE 5%
R 1
J 0
(-6675 7225);
DISPLAY 0.978723 (-6675 7225);
PAINT SKYBLUE (-6675 7225);
DISPLAY INVISIBLE (-6675 7225);
FORCEPROP 1 LAST PACK_TYPE 0402LF
R 1
J 0
(-6625 7475);
DISPLAY 0.978723 (-6625 7475);
PAINT SKYBLUE (-6625 7475);
DISPLAY INVISIBLE (-6625 7475);
FORCEPROP 1 LAST PATH I62
R 1
J 0
(-6925 7175);
DISPLAY 0.978723 (-6925 7175);
PAINT WHITE (-6925 7175);
DISPLAY INVISIBLE (-6925 7175);
FORCEPROP 1 LAST PART_NUMBER CS24702JB10
R 1
J 0
(-6875 7175);
DISPLAY 0.978723 (-6875 7175);
PAINT SKYBLUE (-6875 7175);
DISPLAY INVISIBLE (-6875 7175);
FORCEADD UNIVERSAL_GND..1
(-6775 7075);
FORCEPROP 3 LASTPIN (-6775 7125) SIG_NAME GND\g
J 0
(-6765 7135);
DISPLAY 0.659574 (-6765 7135);
PAINT MONO (-6765 7135);
DISPLAY INVISIBLE (-6765 7135);
FORCEPROP 2 LAST CDS_LIB pure_quanta_power
J 0
(-6775 7075);
DISPLAY INVISIBLE (-6775 7075);
FORCEPROP 1 LAST HDL_POWER GND
J 1
(-6750 7000);
DISPLAY 0.872340 (-6750 7000);
PAINT GREEN (-6750 7000);
DISPLAY INVISIBLE (-6750 7000);
FORCEPROP 1 LAST PATH I63
J 0
(-6700 7075);
DISPLAY 0.872340 (-6700 7075);
PAINT AQUA (-6700 7075);
DISPLAY INVISIBLE (-6700 7075);
FORCEADD Q_RES..1
R 1
(-7075 7750);
FORCEPROP 1 LAST LOCATION R446
J 0
(-7050 7675);
DISPLAY 0.489362 (-7050 7675);
PAINT SKYBLUE (-7050 7675);
FORCEPROP 2 LAST $SEC 1
J 0
(-7050 7800);
DISPLAY 0.680851 (-7050 7800);
PAINT MONO (-7050 7800);
DISPLAY INVISIBLE (-7050 7800);
FORCEPROP 2 LAST CDS_SEC 1
J 0
(-7050 7800);
DISPLAY 1.021277 (-7050 7800);
DISPLAY INVISIBLE (-7050 7800);
FORCEPROP 1 LASTPIN (-7075 7650) $PN 1
R 1
J 0
(-7087 7662);
DISPLAY 0.489362 (-7087 7662);
PAINT MONO (-7087 7662);
FORCEPROP 1 LASTPIN (-7075 7850) $PN 2
R 1
J 0
(-7087 7812);
DISPLAY 0.489362 (-7087 7812);
PAINT MONO (-7087 7812);
FORCEPROP 1 LAST MATERIAL CHIP
J 0
(-7050 7775);
DISPLAY 0.489362 (-7050 7775);
PAINT SKYBLUE (-7050 7775);
FORCEPROP 1 LAST VALUE 4.7K
J 0
(-7050 7725);
DISPLAY 0.489362 (-7050 7725);
PAINT SKYBLUE (-7050 7725);
FORCEPROP 1 LAST PACK_TYPE 0402LF
R 1
J 0
(-6925 8000);
DISPLAY 0.978723 (-6925 8000);
PAINT SKYBLUE (-6925 8000);
DISPLAY INVISIBLE (-6925 8000);
FORCEPROP 1 LAST TOLERANCE 5%
R 1
J 0
(-6975 7750);
DISPLAY 0.978723 (-6975 7750);
PAINT SKYBLUE (-6975 7750);
DISPLAY INVISIBLE (-6975 7750);
FORCEPROP 1 LAST WATTAGE 1/16W
R 1
J 2
(-6925 7725);
DISPLAY 0.978723 (-6925 7725);
PAINT SKYBLUE (-6925 7725);
DISPLAY INVISIBLE (-6925 7725);
FORCEPROP 2 LAST CDS_LIB pure_quanta
J 0
(-7075 7750);
DISPLAY INVISIBLE (-7075 7750);
FORCEPROP 1 LAST PATH I64
R 1
J 0
(-7225 7700);
DISPLAY 0.978723 (-7225 7700);
PAINT WHITE (-7225 7700);
DISPLAY INVISIBLE (-7225 7700);
FORCEPROP 1 LAST PART_NUMBER CS24702JB10
R 1
J 0
(-7175 7700);
DISPLAY 0.978723 (-7175 7700);
PAINT SKYBLUE (-7175 7700);
DISPLAY INVISIBLE (-7175 7700);
FORCEADD Q_RES..1
R 1
(-6775 7750);
FORCEPROP 1 LAST LOCATION R447
J 0
(-6750 7675);
DISPLAY 0.489362 (-6750 7675);
PAINT SKYBLUE (-6750 7675);
FORCEPROP 2 LAST $SEC 1
J 0
(-6750 7800);
DISPLAY 0.680851 (-6750 7800);
PAINT MONO (-6750 7800);
DISPLAY INVISIBLE (-6750 7800);
FORCEPROP 2 LAST CDS_SEC 1
J 0
(-6750 7800);
DISPLAY 1.021277 (-6750 7800);
DISPLAY INVISIBLE (-6750 7800);
FORCEPROP 1 LASTPIN (-6775 7650) $PN 1
R 1
J 0
(-6787 7662);
DISPLAY 0.489362 (-6787 7662);
PAINT MONO (-6787 7662);
FORCEPROP 1 LASTPIN (-6775 7850) $PN 2
R 1
J 0
(-6787 7812);
DISPLAY 0.489362 (-6787 7812);
PAINT MONO (-6787 7812);
FORCEPROP 1 LAST MATERIAL CHIP
J 0
(-6750 7775);
DISPLAY 0.489362 (-6750 7775);
PAINT SKYBLUE (-6750 7775);
FORCEPROP 1 LAST VALUE 4.7K
J 0
(-6750 7725);
DISPLAY 0.489362 (-6750 7725);
PAINT SKYBLUE (-6750 7725);
FORCEPROP 1 LAST PACK_TYPE 0402LF
R 1
J 0
(-6625 8000);
DISPLAY 0.978723 (-6625 8000);
PAINT SKYBLUE (-6625 8000);
DISPLAY INVISIBLE (-6625 8000);
FORCEPROP 1 LAST TOLERANCE 5%
R 1
J 0
(-6675 7750);
DISPLAY 0.978723 (-6675 7750);
PAINT SKYBLUE (-6675 7750);
DISPLAY INVISIBLE (-6675 7750);
FORCEPROP 1 LAST WATTAGE 1/16W
R 1
J 2
(-6625 7725);
DISPLAY 0.978723 (-6625 7725);
PAINT SKYBLUE (-6625 7725);
DISPLAY INVISIBLE (-6625 7725);
FORCEPROP 2 LAST CDS_LIB pure_quanta
J 0
(-6775 7750);
DISPLAY INVISIBLE (-6775 7750);
FORCEPROP 1 LAST PATH I65
R 1
J 0
(-6925 7700);
DISPLAY 0.978723 (-6925 7700);
PAINT WHITE (-6925 7700);
DISPLAY INVISIBLE (-6925 7700);
FORCEPROP 1 LAST PART_NUMBER CS24702JB10
R 1
J 0
(-6875 7700);
DISPLAY 0.978723 (-6875 7700);
PAINT SKYBLUE (-6875 7700);
DISPLAY INVISIBLE (-6875 7700);
FORCEADD Q_RES..1
R 1
(-6925 7750);
FORCEPROP 1 LAST LOCATION R445
J 0
(-6900 7675);
DISPLAY 0.489362 (-6900 7675);
PAINT SKYBLUE (-6900 7675);
FORCEPROP 2 LAST $SEC 1
J 0
(-6900 7800);
DISPLAY 0.680851 (-6900 7800);
PAINT MONO (-6900 7800);
DISPLAY INVISIBLE (-6900 7800);
FORCEPROP 2 LAST CDS_SEC 1
J 0
(-6900 7800);
DISPLAY 1.021277 (-6900 7800);
DISPLAY INVISIBLE (-6900 7800);
FORCEPROP 1 LASTPIN (-6925 7650) $PN 1
R 1
J 0
(-6937 7662);
DISPLAY 0.489362 (-6937 7662);
PAINT MONO (-6937 7662);
FORCEPROP 1 LASTPIN (-6925 7850) $PN 2
R 1
J 0
(-6937 7812);
DISPLAY 0.489362 (-6937 7812);
PAINT MONO (-6937 7812);
FORCEPROP 1 LAST VALUE 4.7K
J 0
(-6900 7725);
DISPLAY 0.489362 (-6900 7725);
PAINT SKYBLUE (-6900 7725);
FORCEPROP 1 LAST MATERIAL CHIP
J 0
(-6900 7775);
DISPLAY 0.489362 (-6900 7775);
PAINT SKYBLUE (-6900 7775);
FORCEPROP 1 LAST PACK_TYPE 0402LF
R 1
J 0
(-6775 8000);
DISPLAY 0.978723 (-6775 8000);
PAINT SKYBLUE (-6775 8000);
DISPLAY INVISIBLE (-6775 8000);
FORCEPROP 1 LAST TOLERANCE 5%
R 1
J 0
(-6825 7750);
DISPLAY 0.978723 (-6825 7750);
PAINT SKYBLUE (-6825 7750);
DISPLAY INVISIBLE (-6825 7750);
FORCEPROP 1 LAST WATTAGE 1/16W
R 1
J 2
(-6775 7725);
DISPLAY 0.978723 (-6775 7725);
PAINT SKYBLUE (-6775 7725);
DISPLAY INVISIBLE (-6775 7725);
FORCEPROP 2 LAST CDS_LIB pure_quanta
J 0
(-6925 7750);
DISPLAY INVISIBLE (-6925 7750);
FORCEPROP 1 LAST PATH I66
R 1
J 0
(-7075 7700);
DISPLAY 0.978723 (-7075 7700);
PAINT WHITE (-7075 7700);
DISPLAY INVISIBLE (-7075 7700);
FORCEPROP 1 LAST PART_NUMBER CS24702JB10
R 1
J 0
(-7025 7700);
DISPLAY 0.978723 (-7025 7700);
PAINT SKYBLUE (-7025 7700);
DISPLAY INVISIBLE (-7025 7700);
FORCEADD UNIVERSAL_GND..1
(-6225 7600);
FORCEPROP 3 LASTPIN (-6225 7650) SIG_NAME GND\g
J 0
(-6215 7660);
DISPLAY 0.659574 (-6215 7660);
PAINT MONO (-6215 7660);
DISPLAY INVISIBLE (-6215 7660);
FORCEPROP 2 LAST CDS_LIB pure_quanta_power
J 0
(-6225 7600);
DISPLAY INVISIBLE (-6225 7600);
FORCEPROP 1 LAST HDL_POWER GND
J 1
(-6200 7525);
DISPLAY 0.872340 (-6200 7525);
PAINT GREEN (-6200 7525);
DISPLAY INVISIBLE (-6200 7525);
FORCEPROP 1 LAST PATH I68
J 0
(-6150 7600);
DISPLAY 0.872340 (-6150 7600);
PAINT AQUA (-6150 7600);
DISPLAY INVISIBLE (-6150 7600);
FORCEADD Q_RES..1
(-7775 8975);
FORCEPROP 1 LAST LOCATION R938
J 0
(-7975 8975);
DISPLAY 0.489362 (-7975 8975);
PAINT SKYBLUE (-7975 8975);
FORCEPROP 0 LAST $SEC 1
J 0
(-7900 9025);
DISPLAY 0.680851 (-7900 9025);
PAINT MONO (-7900 9025);
DISPLAY INVISIBLE (-7900 9025);
FORCEPROP 0 LAST CDS_SEC 1
J 0
(-7900 9025);
DISPLAY 0.680851 (-7900 9025);
DISPLAY INVISIBLE (-7900 9025);
FORCEPROP 1 LASTPIN (-7875 8975) $PN 1
J 0
(-7863 8987);
DISPLAY 0.489362 (-7863 8987);
PAINT MONO (-7863 8987);
FORCEPROP 1 LASTPIN (-7675 8975) $PN 2
J 0
(-7713 8987);
DISPLAY 0.489362 (-7713 8987);
PAINT MONO (-7713 8987);
FORCEPROP 1 LAST VALUE 4.7K
J 0
(-7675 8975);
DISPLAY 0.489362 (-7675 8975);
PAINT SKYBLUE (-7675 8975);
FORCEPROP 1 LAST PACK_TYPE 0402LF
J 0
(-7525 8825);
DISPLAY 0.510638 (-7525 8825);
PAINT SKYBLUE (-7525 8825);
DISPLAY INVISIBLE (-7525 8825);
FORCEPROP 1 LAST TOLERANCE 5%
J 0
(-7650 8975);
DISPLAY 0.510638 (-7650 8975);
PAINT SKYBLUE (-7650 8975);
DISPLAY INVISIBLE (-7650 8975);
FORCEPROP 1 LAST MATERIAL CHIP
J 0
(-7675 8950);
DISPLAY 0.489362 (-7675 8950);
PAINT SKYBLUE (-7675 8950);
DISPLAY INVISIBLE (-7675 8950);
FORCEPROP 1 LAST WATTAGE 1/16W
J 2
(-7800 8825);
DISPLAY 0.510638 (-7800 8825);
PAINT SKYBLUE (-7800 8825);
DISPLAY INVISIBLE (-7800 8825);
FORCEPROP 2 LAST CDS_LIB pure_quanta
J 0
(-7775 8975);
DISPLAY INVISIBLE (-7775 8975);
FORCEPROP 1 LAST PATH I69
J 0
(-7825 9125);
DISPLAY 0.978723 (-7825 9125);
PAINT WHITE (-7825 9125);
DISPLAY INVISIBLE (-7825 9125);
FORCEPROP 1 LAST PART_NUMBER CS24702JB10
J 0
(-7825 9075);
DISPLAY 0.510638 (-7825 9075);
PAINT SKYBLUE (-7825 9075);
DISPLAY INVISIBLE (-7825 9075);
FORCEADD OFFPAGE..2
R 2
(-8775 7650);
FORCEPROP 2 LAST $XR2 255 
J 0
(-9209 7650);
DISPLAY 0.638298 (-9209 7650);
PAINT MONO (-9209 7650);
FORCEPROP 2 LAST $XR1 28 
J 0
(-9089 7650);
DISPLAY 0.638298 (-9089 7650);
PAINT MONO (-9089 7650);
FORCEPROP 2 LAST $XR0 81 
J 0
(-8999 7650);
DISPLAY 0.638298 (-8999 7650);
PAINT MONO (-8999 7650);
FORCEPROP 2 LAST CDS_LIB standard
J 0
(-8775 7650);
DISPLAY INVISIBLE (-8775 7650);
FORCEPROP 1 LAST OFFPAGE TRUE
J 2
(-9100 7525);
DISPLAY 0.872340 (-9100 7525);
PAINT GREEN (-9100 7525);
DISPLAY INVISIBLE (-9100 7525);
FORCEPROP 1 LAST COMMENT_BODY TRUE
J 2
(-8730 7555);
DISPLAY 0.872340 (-8730 7555);
PAINT GREEN (-8730 7555);
DISPLAY INVISIBLE (-8730 7555);
FORCEPROP 2 LAST PATH I7
J 0
(-8975 7700);
DISPLAY 0.680851 (-8975 7700);
DISPLAY INVISIBLE (-8975 7700);
FORCEADD OFFPAGE..2
(-7675 9325);
FORCEPROP 2 LAST $XR1 159 
J 0
(-7396 9325);
DISPLAY 0.638298 (-7396 9325);
PAINT MONO (-7396 9325);
FORCEPROP 2 LAST $XR0 28 
J 0
(-7486 9325);
DISPLAY 0.638298 (-7486 9325);
PAINT MONO (-7486 9325);
FORCEPROP 2 LAST CDS_LIB standard
J 0
(-7675 9325);
DISPLAY INVISIBLE (-7675 9325);
FORCEPROP 1 LAST OFFPAGE TRUE
J 0
(-7350 9200);
DISPLAY 0.872340 (-7350 9200);
PAINT GREEN (-7350 9200);
DISPLAY INVISIBLE (-7350 9200);
FORCEPROP 1 LAST COMMENT_BODY TRUE
J 0
(-7720 9230);
DISPLAY 0.872340 (-7720 9230);
PAINT PEACH (-7720 9230);
DISPLAY INVISIBLE (-7720 9230);
FORCEPROP 2 LAST PATH I70
J 0
(-7375 9375);
DISPLAY 0.680851 (-7375 9375);
DISPLAY INVISIBLE (-7375 9375);
FORCEADD OFFPAGE..2
(-7675 9375);
FORCEPROP 2 LAST $XR1 159 
J 0
(-7396 9375);
DISPLAY 0.638298 (-7396 9375);
PAINT MONO (-7396 9375);
FORCEPROP 2 LAST $XR0 28 
J 0
(-7486 9375);
DISPLAY 0.638298 (-7486 9375);
PAINT MONO (-7486 9375);
FORCEPROP 2 LAST CDS_LIB standard
J 0
(-7675 9375);
DISPLAY INVISIBLE (-7675 9375);
FORCEPROP 1 LAST OFFPAGE TRUE
J 0
(-7350 9250);
DISPLAY 0.872340 (-7350 9250);
PAINT GREEN (-7350 9250);
DISPLAY INVISIBLE (-7350 9250);
FORCEPROP 1 LAST COMMENT_BODY TRUE
J 0
(-7720 9280);
DISPLAY 0.872340 (-7720 9280);
PAINT PEACH (-7720 9280);
DISPLAY INVISIBLE (-7720 9280);
FORCEPROP 2 LAST PATH I71
J 0
(-7375 9425);
DISPLAY 0.680851 (-7375 9425);
DISPLAY INVISIBLE (-7375 9425);
FORCEADD OFFPAGE..2
(-7675 9425);
FORCEPROP 2 LAST $XR1 159 
J 0
(-7396 9425);
DISPLAY 0.638298 (-7396 9425);
PAINT MONO (-7396 9425);
FORCEPROP 2 LAST $XR0 28 
J 0
(-7486 9425);
DISPLAY 0.638298 (-7486 9425);
PAINT MONO (-7486 9425);
FORCEPROP 2 LAST CDS_LIB standard
J 0
(-7675 9425);
DISPLAY INVISIBLE (-7675 9425);
FORCEPROP 1 LAST OFFPAGE TRUE
J 0
(-7350 9300);
DISPLAY 0.872340 (-7350 9300);
PAINT GREEN (-7350 9300);
DISPLAY INVISIBLE (-7350 9300);
FORCEPROP 1 LAST COMMENT_BODY TRUE
J 0
(-7720 9330);
DISPLAY 0.872340 (-7720 9330);
PAINT PEACH (-7720 9330);
DISPLAY INVISIBLE (-7720 9330);
FORCEPROP 2 LAST PATH I72
J 0
(-7375 9475);
DISPLAY 0.680851 (-7375 9475);
DISPLAY INVISIBLE (-7375 9475);
FORCEADD OFFPAGE..2
(-7675 9475);
FORCEPROP 2 LAST $XR1 159 
J 0
(-7396 9475);
DISPLAY 0.638298 (-7396 9475);
PAINT MONO (-7396 9475);
FORCEPROP 2 LAST $XR0 28 
J 0
(-7486 9475);
DISPLAY 0.638298 (-7486 9475);
PAINT MONO (-7486 9475);
FORCEPROP 2 LAST CDS_LIB standard
J 0
(-7675 9475);
DISPLAY INVISIBLE (-7675 9475);
FORCEPROP 1 LAST OFFPAGE TRUE
J 0
(-7350 9350);
DISPLAY 0.872340 (-7350 9350);
PAINT GREEN (-7350 9350);
DISPLAY INVISIBLE (-7350 9350);
FORCEPROP 1 LAST COMMENT_BODY TRUE
J 0
(-7720 9380);
DISPLAY 0.872340 (-7720 9380);
PAINT PEACH (-7720 9380);
DISPLAY INVISIBLE (-7720 9380);
FORCEPROP 2 LAST PATH I73
J 0
(-7375 9525);
DISPLAY 0.680851 (-7375 9525);
DISPLAY INVISIBLE (-7375 9525);
FORCEADD UNIVERSAL_POWER..1
(-7425 9075);
FORCEPROP 3 LASTPIN (-7425 9025) SIG_NAME PVDD18_S5_P0\g
J 0
(-7415 9035);
DISPLAY 0.659574 (-7415 9035);
PAINT MONO (-7415 9035);
DISPLAY INVISIBLE (-7415 9035);
FORCEPROP 1 LAST HDL_POWER PVDD18_S5_P0
J 1
(-7425 9125);
DISPLAY 0.489362 (-7425 9125);
PAINT GREEN (-7425 9125);
FORCEPROP 2 LAST CDS_LIB pure_quanta_power
J 0
(-7425 9075);
DISPLAY INVISIBLE (-7425 9075);
FORCEPROP 1 LAST PATH I74
J 0
(-7375 9100);
DISPLAY 0.872340 (-7375 9100);
PAINT AQUA (-7375 9100);
DISPLAY INVISIBLE (-7375 9100);
FORCEADD OFFPAGE..1
(-7300 9675);
FORCEPROP 2 LAST $XR0 76 
J 0
(-7521 9675);
DISPLAY 0.638298 (-7521 9675);
PAINT MONO (-7521 9675);
FORCEPROP 2 LAST CDS_LIB standard
J 0
(-7300 9675);
DISPLAY INVISIBLE (-7300 9675);
FORCEPROP 1 LAST OFFPAGE TRUE
J 0
(-6975 9550);
DISPLAY 0.872340 (-6975 9550);
PAINT GREEN (-6975 9550);
DISPLAY INVISIBLE (-6975 9550);
FORCEPROP 1 LAST COMMENT_BODY TRUE
J 0
(-7175 9575);
DISPLAY 0.872340 (-7175 9575);
PAINT GREEN (-7175 9575);
DISPLAY INVISIBLE (-7175 9575);
FORCEPROP 2 LAST PATH I75
J 0
(-7500 9725);
DISPLAY 0.680851 (-7500 9725);
DISPLAY INVISIBLE (-7500 9725);
FORCEADD OFFPAGE..4
R 2
(-7300 9825);
FORCEPROP 2 LAST $XR1 167 
J 0
(-7641 9825);
DISPLAY 0.638298 (-7641 9825);
PAINT MONO (-7641 9825);
FORCEPROP 2 LAST $XR0 81 
J 0
(-7521 9825);
DISPLAY 0.638298 (-7521 9825);
PAINT MONO (-7521 9825);
FORCEPROP 2 LAST $XR2 165 
J 0
(-7761 9825);
DISPLAY 0.638298 (-7761 9825);
PAINT MONO (-7761 9825);
FORCEPROP 2 LAST CDS_LIB standard
J 0
(-7300 9825);
DISPLAY INVISIBLE (-7300 9825);
FORCEPROP 1 LAST OFFPAGE TRUE
J 2
(-7625 9700);
DISPLAY 0.872340 (-7625 9700);
PAINT GREEN (-7625 9700);
DISPLAY INVISIBLE (-7625 9700);
FORCEPROP 1 LAST COMMENT_BODY TRUE
J 2
(-7275 9725);
DISPLAY 0.872340 (-7275 9725);
PAINT GREEN (-7275 9725);
DISPLAY INVISIBLE (-7275 9725);
FORCEPROP 2 LAST PATH I76
J 0
(-7500 9875);
DISPLAY 0.680851 (-7500 9875);
DISPLAY INVISIBLE (-7500 9875);
FORCEADD OFFPAGE..2
R 2
(-7300 9875);
FORCEPROP 2 LAST $XR1 166 
J 0
(-7644 9875);
DISPLAY 0.638298 (-7644 9875);
PAINT MONO (-7644 9875);
FORCEPROP 2 LAST $XR0 28 
J 0
(-7524 9875);
DISPLAY 0.638298 (-7524 9875);
PAINT MONO (-7524 9875);
FORCEPROP 2 LAST CDS_LIB standard
J 0
(-7300 9875);
DISPLAY INVISIBLE (-7300 9875);
FORCEPROP 1 LAST OFFPAGE TRUE
J 2
(-7625 9750);
DISPLAY 0.872340 (-7625 9750);
PAINT GREEN (-7625 9750);
DISPLAY INVISIBLE (-7625 9750);
FORCEPROP 1 LAST COMMENT_BODY TRUE
J 2
(-7255 9780);
DISPLAY 0.872340 (-7255 9780);
PAINT GREEN (-7255 9780);
DISPLAY INVISIBLE (-7255 9780);
FORCEPROP 2 LAST PATH I77
J 0
(-7500 9925);
DISPLAY 0.680851 (-7500 9925);
DISPLAY INVISIBLE (-7500 9925);
FORCEADD OFFPAGE..2
R 2
(-7300 9925);
FORCEPROP 2 LAST $XR1 166 
J 0
(-7644 9925);
DISPLAY 0.638298 (-7644 9925);
PAINT MONO (-7644 9925);
FORCEPROP 2 LAST $XR0 34 
J 0
(-7524 9925);
DISPLAY 0.638298 (-7524 9925);
PAINT MONO (-7524 9925);
FORCEPROP 2 LAST CDS_LIB standard
J 0
(-7300 9925);
DISPLAY INVISIBLE (-7300 9925);
FORCEPROP 1 LAST OFFPAGE TRUE
J 2
(-7625 9800);
DISPLAY 0.872340 (-7625 9800);
PAINT GREEN (-7625 9800);
DISPLAY INVISIBLE (-7625 9800);
FORCEPROP 1 LAST COMMENT_BODY TRUE
J 2
(-7255 9830);
DISPLAY 0.872340 (-7255 9830);
PAINT GREEN (-7255 9830);
DISPLAY INVISIBLE (-7255 9830);
FORCEPROP 2 LAST PATH I78
J 0
(-7500 9975);
DISPLAY 0.680851 (-7500 9975);
DISPLAY INVISIBLE (-7500 9975);
FORCEADD OFFPAGE..2
R 2
(-7900 10825);
FORCEPROP 2 LAST $XR0 151 
J 0
(-8185 10825);
DISPLAY 0.638298 (-8185 10825);
PAINT MONO (-8185 10825);
FORCEPROP 2 LAST CDS_LIB standard
J 0
(-7900 10825);
DISPLAY INVISIBLE (-7900 10825);
FORCEPROP 1 LAST OFFPAGE TRUE
J 2
(-8225 10700);
DISPLAY 0.872340 (-8225 10700);
PAINT GREEN (-8225 10700);
DISPLAY INVISIBLE (-8225 10700);
FORCEPROP 1 LAST COMMENT_BODY TRUE
J 2
(-7855 10730);
DISPLAY 0.872340 (-7855 10730);
PAINT GREEN (-7855 10730);
DISPLAY INVISIBLE (-7855 10730);
FORCEPROP 2 LAST PATH I79
J 0
(-8175 10875);
DISPLAY 0.680851 (-8175 10875);
DISPLAY INVISIBLE (-8175 10875);
FORCEADD OFFPAGE..2
R 2
(-8750 8175);
FORCEPROP 2 LAST $XR1 28 
J 0
(-9064 8175);
DISPLAY 0.638298 (-9064 8175);
PAINT MONO (-9064 8175);
FORCEPROP 2 LAST $XR0 82 
J 0
(-8974 8175);
DISPLAY 0.638298 (-8974 8175);
PAINT MONO (-8974 8175);
FORCEPROP 2 LAST CDS_LIB standard
J 0
(-8750 8175);
DISPLAY INVISIBLE (-8750 8175);
FORCEPROP 1 LAST OFFPAGE TRUE
J 2
(-9075 8050);
DISPLAY 0.872340 (-9075 8050);
PAINT GREEN (-9075 8050);
DISPLAY INVISIBLE (-9075 8050);
FORCEPROP 1 LAST COMMENT_BODY TRUE
J 2
(-8705 8080);
DISPLAY 0.872340 (-8705 8080);
PAINT GREEN (-8705 8080);
DISPLAY INVISIBLE (-8705 8080);
FORCEPROP 2 LAST PATH I8
J 0
(-8950 8225);
DISPLAY 0.680851 (-8950 8225);
DISPLAY INVISIBLE (-8950 8225);
FORCEADD OFFPAGE..3
R 2
(-7900 10775);
FORCEPROP 2 LAST $XR0 151 
J 0
(-8210 10775);
DISPLAY 0.638298 (-8210 10775);
PAINT MONO (-8210 10775);
FORCEPROP 2 LAST CDS_LIB standard
J 0
(-7900 10775);
DISPLAY INVISIBLE (-7900 10775);
FORCEPROP 1 LAST OFFPAGE TRUE
J 2
(-8225 10650);
DISPLAY 0.872340 (-8225 10650);
PAINT GREEN (-8225 10650);
DISPLAY INVISIBLE (-8225 10650);
FORCEPROP 1 LAST COMMENT_BODY TRUE
J 2
(-7850 10675);
DISPLAY 0.872340 (-7850 10675);
PAINT PEACH (-7850 10675);
DISPLAY INVISIBLE (-7850 10675);
FORCEPROP 2 LAST PATH I80
J 0
(-8200 10825);
DISPLAY 0.680851 (-8200 10825);
DISPLAY INVISIBLE (-8200 10825);
FORCEADD OFFPAGE..3
R 2
(-7900 10875);
FORCEPROP 2 LAST $XR0 34 
J 0
(-8179 10875);
DISPLAY 0.638298 (-8179 10875);
PAINT MONO (-8179 10875);
FORCEPROP 2 LAST CDS_LIB standard
J 0
(-7900 10875);
DISPLAY INVISIBLE (-7900 10875);
FORCEPROP 1 LAST OFFPAGE TRUE
J 2
(-8225 10750);
DISPLAY 0.872340 (-8225 10750);
PAINT GREEN (-8225 10750);
DISPLAY INVISIBLE (-8225 10750);
FORCEPROP 1 LAST COMMENT_BODY TRUE
J 2
(-7850 10775);
DISPLAY 0.872340 (-7850 10775);
PAINT PEACH (-7850 10775);
DISPLAY INVISIBLE (-7850 10775);
FORCEPROP 2 LAST PATH I81
J 0
(-8175 10925);
DISPLAY 0.680851 (-8175 10925);
DISPLAY INVISIBLE (-8175 10925);
FORCEADD OFFPAGE..2
R 2
(-7900 10925);
FORCEPROP 2 LAST $XR0 34 
J 0
(-8124 10925);
DISPLAY 0.638298 (-8124 10925);
PAINT MONO (-8124 10925);
FORCEPROP 2 LAST CDS_LIB standard
J 2
(-7900 10925);
DISPLAY INVISIBLE (-7900 10925);
FORCEPROP 1 LAST OFFPAGE TRUE
J 2
(-8225 10800);
DISPLAY 0.872340 (-8225 10800);
PAINT GREEN (-8225 10800);
DISPLAY INVISIBLE (-8225 10800);
FORCEPROP 1 LAST COMMENT_BODY TRUE
J 2
(-7855 10830);
DISPLAY 0.872340 (-7855 10830);
PAINT GREEN (-7855 10830);
DISPLAY INVISIBLE (-7855 10830);
FORCEPROP 2 LAST PATH I83
J 0
(-8150 10975);
DISPLAY 0.680851 (-8150 10975);
DISPLAY INVISIBLE (-8150 10975);
FORCEADD OFFPAGE..4
R 2
(-7300 10175);
FORCEPROP 2 LAST $XR1 82 
J 0
(-7611 10175);
DISPLAY 0.638298 (-7611 10175);
PAINT MONO (-7611 10175);
FORCEPROP 2 LAST $XR0 28 
J 0
(-7521 10175);
DISPLAY 0.638298 (-7521 10175);
PAINT MONO (-7521 10175);
FORCEPROP 2 LAST CDS_LIB standard
J 0
(-7300 10175);
DISPLAY INVISIBLE (-7300 10175);
FORCEPROP 1 LAST OFFPAGE TRUE
J 2
(-7625 10050);
DISPLAY 0.872340 (-7625 10050);
PAINT GREEN (-7625 10050);
DISPLAY INVISIBLE (-7625 10050);
FORCEPROP 1 LAST COMMENT_BODY TRUE
J 2
(-7275 10075);
DISPLAY 0.872340 (-7275 10075);
PAINT GREEN (-7275 10075);
DISPLAY INVISIBLE (-7275 10075);
FORCEPROP 2 LAST PATH I85
J 0
(-7550 10225);
DISPLAY 0.680851 (-7550 10225);
DISPLAY INVISIBLE (-7550 10225);
FORCEADD OFFPAGE..4
R 2
(-7300 10125);
FORCEPROP 2 LAST $XR1 82 
J 0
(-7611 10125);
DISPLAY 0.638298 (-7611 10125);
PAINT MONO (-7611 10125);
FORCEPROP 2 LAST $XR0 28 
J 0
(-7521 10125);
DISPLAY 0.638298 (-7521 10125);
PAINT MONO (-7521 10125);
FORCEPROP 2 LAST CDS_LIB standard
J 0
(-7300 10125);
DISPLAY INVISIBLE (-7300 10125);
FORCEPROP 1 LAST OFFPAGE TRUE
J 2
(-7625 10000);
DISPLAY 0.872340 (-7625 10000);
PAINT GREEN (-7625 10000);
DISPLAY INVISIBLE (-7625 10000);
FORCEPROP 1 LAST COMMENT_BODY TRUE
J 2
(-7275 10025);
DISPLAY 0.872340 (-7275 10025);
PAINT GREEN (-7275 10025);
DISPLAY INVISIBLE (-7275 10025);
FORCEPROP 2 LAST PATH I86
J 0
(-7550 10175);
DISPLAY 0.680851 (-7550 10175);
DISPLAY INVISIBLE (-7550 10175);
FORCEADD OFFPAGE..4
R 2
(-7300 10225);
FORCEPROP 2 LAST $XR1 82 
J 0
(-7611 10225);
DISPLAY 0.638298 (-7611 10225);
PAINT MONO (-7611 10225);
FORCEPROP 2 LAST $XR0 28 
J 0
(-7521 10225);
DISPLAY 0.638298 (-7521 10225);
PAINT MONO (-7521 10225);
FORCEPROP 2 LAST CDS_LIB standard
J 0
(-7300 10225);
DISPLAY INVISIBLE (-7300 10225);
FORCEPROP 1 LAST OFFPAGE TRUE
J 2
(-7625 10100);
DISPLAY 0.872340 (-7625 10100);
PAINT GREEN (-7625 10100);
DISPLAY INVISIBLE (-7625 10100);
FORCEPROP 1 LAST COMMENT_BODY TRUE
J 2
(-7275 10125);
DISPLAY 0.872340 (-7275 10125);
PAINT GREEN (-7275 10125);
DISPLAY INVISIBLE (-7275 10125);
FORCEPROP 2 LAST PATH I89
J 0
(-7550 10275);
DISPLAY 0.680851 (-7550 10275);
DISPLAY INVISIBLE (-7550 10275);
FORCEADD OFFPAGE..2
R 2
(-8750 8325);
FORCEPROP 2 LAST $XR1 81 
J 0
(-9064 8325);
DISPLAY 0.638298 (-9064 8325);
PAINT MONO (-9064 8325);
FORCEPROP 2 LAST $XR0 28 
J 0
(-8974 8325);
DISPLAY 0.638298 (-8974 8325);
PAINT MONO (-8974 8325);
FORCEPROP 2 LAST CDS_LIB standard
J 0
(-8750 8325);
DISPLAY INVISIBLE (-8750 8325);
FORCEPROP 1 LAST OFFPAGE TRUE
J 2
(-9075 8200);
DISPLAY 0.872340 (-9075 8200);
PAINT GREEN (-9075 8200);
DISPLAY INVISIBLE (-9075 8200);
FORCEPROP 1 LAST COMMENT_BODY TRUE
J 2
(-8705 8230);
DISPLAY 0.872340 (-8705 8230);
PAINT GREEN (-8705 8230);
DISPLAY INVISIBLE (-8705 8230);
FORCEPROP 2 LAST PATH I9
J 0
(-8950 8375);
DISPLAY 0.680851 (-8950 8375);
DISPLAY INVISIBLE (-8950 8375);
FORCEADD OFFPAGE..4
R 2
(-7300 10325);
FORCEPROP 2 LAST $XR0 167 
J 0
(-7552 10325);
DISPLAY 0.638298 (-7552 10325);
PAINT MONO (-7552 10325);
FORCEPROP 2 LAST CDS_LIB standard
J 0
(-7300 10325);
DISPLAY INVISIBLE (-7300 10325);
FORCEPROP 1 LAST OFFPAGE TRUE
J 2
(-7625 10200);
DISPLAY 0.872340 (-7625 10200);
PAINT GREEN (-7625 10200);
DISPLAY INVISIBLE (-7625 10200);
FORCEPROP 1 LAST COMMENT_BODY TRUE
J 2
(-7275 10225);
DISPLAY 0.872340 (-7275 10225);
PAINT GREEN (-7275 10225);
DISPLAY INVISIBLE (-7275 10225);
FORCEPROP 2 LAST PATH I90
J 0
(-7550 10375);
DISPLAY 0.680851 (-7550 10375);
DISPLAY INVISIBLE (-7550 10375);
FORCEADD OFFPAGE..2
R 2
(-7300 10375);
FORCEPROP 2 LAST $XR1 81 
J 0
(-7614 10375);
DISPLAY 0.638298 (-7614 10375);
PAINT MONO (-7614 10375);
FORCEPROP 2 LAST $XR0 28 
J 0
(-7524 10375);
DISPLAY 0.638298 (-7524 10375);
PAINT MONO (-7524 10375);
FORCEPROP 2 LAST CDS_LIB standard
J 2
(-7300 10375);
DISPLAY INVISIBLE (-7300 10375);
FORCEPROP 1 LAST OFFPAGE TRUE
J 2
(-7625 10250);
DISPLAY 0.872340 (-7625 10250);
PAINT GREEN (-7625 10250);
DISPLAY INVISIBLE (-7625 10250);
FORCEPROP 1 LAST COMMENT_BODY TRUE
J 2
(-7255 10280);
DISPLAY 0.872340 (-7255 10280);
PAINT GREEN (-7255 10280);
DISPLAY INVISIBLE (-7255 10280);
FORCEPROP 2 LAST PATH I91
J 0
(-7500 10425);
DISPLAY 0.680851 (-7500 10425);
DISPLAY INVISIBLE (-7500 10425);
FORCEADD OFFPAGE..4
R 2
(-7300 10275);
FORCEPROP 2 LAST $XR1 82 
J 0
(-7611 10275);
DISPLAY 0.638298 (-7611 10275);
PAINT MONO (-7611 10275);
FORCEPROP 2 LAST $XR0 28 
J 0
(-7521 10275);
DISPLAY 0.638298 (-7521 10275);
PAINT MONO (-7521 10275);
FORCEPROP 2 LAST CDS_LIB standard
J 0
(-7300 10275);
DISPLAY INVISIBLE (-7300 10275);
FORCEPROP 1 LAST OFFPAGE TRUE
J 2
(-7625 10150);
DISPLAY 0.872340 (-7625 10150);
PAINT GREEN (-7625 10150);
DISPLAY INVISIBLE (-7625 10150);
FORCEPROP 1 LAST COMMENT_BODY TRUE
J 2
(-7275 10175);
DISPLAY 0.872340 (-7275 10175);
PAINT GREEN (-7275 10175);
DISPLAY INVISIBLE (-7275 10175);
FORCEPROP 2 LAST PATH I92
J 0
(-7550 10325);
DISPLAY 0.680851 (-7550 10325);
DISPLAY INVISIBLE (-7550 10325);
FORCEADD Q_RES..1
R 2
(-6375 9925);
FORCEPROP 1 LAST LOCATION R939
J 2
(-6500 9925);
DISPLAY 0.489362 (-6500 9925);
PAINT SKYBLUE (-6500 9925);
FORCEPROP 0 LAST $SEC 1
J 0
(-6450 9975);
DISPLAY 0.680851 (-6450 9975);
PAINT MONO (-6450 9975);
DISPLAY INVISIBLE (-6450 9975);
FORCEPROP 0 LAST CDS_SEC 1
J 0
(-6450 9975);
DISPLAY 0.680851 (-6450 9975);
DISPLAY INVISIBLE (-6450 9975);
FORCEPROP 1 LASTPIN (-6275 9925) $PN 1
J 2
(-6287 9937);
DISPLAY 0.489362 (-6287 9937);
PAINT MONO (-6287 9937);
FORCEPROP 1 LASTPIN (-6475 9925) $PN 2
J 2
(-6437 9937);
DISPLAY 0.489362 (-6437 9937);
PAINT MONO (-6437 9937);
FORCEPROP 1 LAST VALUE 0
J 0
(-6275 9925);
DISPLAY 0.489362 (-6275 9925);
PAINT SKYBLUE (-6275 9925);
FORCEPROP 1 LAST PACK_TYPE 0402LF
J 2
(-6425 9850);
DISPLAY 0.489362 (-6425 9850);
PAINT SKYBLUE (-6425 9850);
DISPLAY INVISIBLE (-6425 9850);
FORCEPROP 1 LAST TOLERANCE 5%
J 2
(-6350 9850);
DISPLAY 0.489362 (-6350 9850);
PAINT SKYBLUE (-6350 9850);
DISPLAY INVISIBLE (-6350 9850);
FORCEPROP 1 LAST MATERIAL CHIP
J 2
(-6800 9850);
DISPLAY 0.489362 (-6800 9850);
PAINT SKYBLUE (-6800 9850);
DISPLAY INVISIBLE (-6800 9850);
FORCEPROP 1 LAST WATTAGE 1/16W
J 0
(-6775 9850);
DISPLAY 0.489362 (-6775 9850);
PAINT SKYBLUE (-6775 9850);
DISPLAY INVISIBLE (-6775 9850);
FORCEPROP 2 LAST CDS_LIB pure_quanta
J 0
(-6375 9925);
DISPLAY INVISIBLE (-6375 9925);
FORCEPROP 1 LAST PATH I93
J 2
(-6325 10075);
DISPLAY 0.978723 (-6325 10075);
PAINT WHITE (-6325 10075);
DISPLAY INVISIBLE (-6325 10075);
FORCEPROP 1 LAST PART_NUMBER CS00002JB13
J 2
(-6400 9975);
DISPLAY 0.489362 (-6400 9975);
PAINT SKYBLUE (-6400 9975);
DISPLAY INVISIBLE (-6400 9975);
FORCEADD Q_RES..1
R 2
(-6375 9875);
FORCEPROP 1 LAST LOCATION R940
J 2
(-6500 9875);
DISPLAY 0.489362 (-6500 9875);
PAINT SKYBLUE (-6500 9875);
FORCEPROP 0 LAST $SEC 1
J 0
(-6450 9925);
DISPLAY 0.680851 (-6450 9925);
PAINT MONO (-6450 9925);
DISPLAY INVISIBLE (-6450 9925);
FORCEPROP 0 LAST CDS_SEC 1
J 0
(-6450 9925);
DISPLAY 0.680851 (-6450 9925);
DISPLAY INVISIBLE (-6450 9925);
FORCEPROP 1 LASTPIN (-6275 9875) $PN 1
J 2
(-6287 9887);
DISPLAY 0.489362 (-6287 9887);
PAINT MONO (-6287 9887);
FORCEPROP 1 LASTPIN (-6475 9875) $PN 2
J 2
(-6437 9887);
DISPLAY 0.489362 (-6437 9887);
PAINT MONO (-6437 9887);
FORCEPROP 1 LAST VALUE 0
J 0
(-6275 9875);
DISPLAY 0.489362 (-6275 9875);
PAINT SKYBLUE (-6275 9875);
FORCEPROP 1 LAST PACK_TYPE 0402LF
J 2
(-6425 9800);
DISPLAY 0.489362 (-6425 9800);
PAINT SKYBLUE (-6425 9800);
DISPLAY INVISIBLE (-6425 9800);
FORCEPROP 1 LAST TOLERANCE 5%
J 2
(-6350 9800);
DISPLAY 0.489362 (-6350 9800);
PAINT SKYBLUE (-6350 9800);
DISPLAY INVISIBLE (-6350 9800);
FORCEPROP 1 LAST MATERIAL CHIP
J 2
(-6800 9800);
DISPLAY 0.489362 (-6800 9800);
PAINT SKYBLUE (-6800 9800);
DISPLAY INVISIBLE (-6800 9800);
FORCEPROP 1 LAST WATTAGE 1/16W
J 0
(-6775 9800);
DISPLAY 0.489362 (-6775 9800);
PAINT SKYBLUE (-6775 9800);
DISPLAY INVISIBLE (-6775 9800);
FORCEPROP 2 LAST CDS_LIB pure_quanta
J 0
(-6375 9875);
DISPLAY INVISIBLE (-6375 9875);
FORCEPROP 1 LAST PATH I94
J 2
(-6325 10025);
DISPLAY 0.978723 (-6325 10025);
PAINT WHITE (-6325 10025);
DISPLAY INVISIBLE (-6325 10025);
FORCEPROP 1 LAST PART_NUMBER CS00002JB13
J 2
(-6400 9925);
DISPLAY 0.489362 (-6400 9925);
PAINT SKYBLUE (-6400 9925);
DISPLAY INVISIBLE (-6400 9925);
FORCEADD Q_RES..1
R 2
(-6850 10775);
FORCEPROP 1 LAST LOCATION R213
J 0
(-6600 10775);
DISPLAY 0.489362 (-6600 10775);
PAINT SKYBLUE (-6600 10775);
FORCEPROP 0 LAST $SEC 1
J 0
(-6600 10825);
DISPLAY 0.680851 (-6600 10825);
PAINT MONO (-6600 10825);
DISPLAY INVISIBLE (-6600 10825);
FORCEPROP 0 LAST CDS_SEC 1
J 0
(-6600 10825);
DISPLAY 1.021277 (-6600 10825);
DISPLAY INVISIBLE (-6600 10825);
FORCEPROP 1 LASTPIN (-6750 10775) $PN 1
J 2
(-6762 10787);
DISPLAY 0.489362 (-6762 10787);
PAINT MONO (-6762 10787);
FORCEPROP 1 LASTPIN (-6950 10775) $PN 2
J 2
(-6912 10787);
DISPLAY 0.489362 (-6912 10787);
PAINT MONO (-6912 10787);
FORCEPROP 1 LAST VALUE 0
J 0
(-6750 10775);
DISPLAY 0.489362 (-6750 10775);
PAINT SKYBLUE (-6750 10775);
FORCEPROP 1 LAST PACK_TYPE 0402LF
J 2
(-6900 10700);
DISPLAY 0.489362 (-6900 10700);
PAINT SKYBLUE (-6900 10700);
DISPLAY INVISIBLE (-6900 10700);
FORCEPROP 1 LAST TOLERANCE 5%
J 2
(-6825 10700);
DISPLAY 0.489362 (-6825 10700);
PAINT SKYBLUE (-6825 10700);
DISPLAY INVISIBLE (-6825 10700);
FORCEPROP 1 LAST MATERIAL CHIP
J 2
(-7275 10700);
DISPLAY 0.489362 (-7275 10700);
PAINT SKYBLUE (-7275 10700);
DISPLAY INVISIBLE (-7275 10700);
FORCEPROP 1 LAST WATTAGE 1/16W
J 0
(-7250 10700);
DISPLAY 0.489362 (-7250 10700);
PAINT SKYBLUE (-7250 10700);
DISPLAY INVISIBLE (-7250 10700);
FORCEPROP 2 LAST CDS_LIB pure_quanta
J 0
(-6850 10775);
DISPLAY INVISIBLE (-6850 10775);
FORCEPROP 1 LAST PATH I95
J 2
(-6800 10925);
DISPLAY 0.978723 (-6800 10925);
PAINT WHITE (-6800 10925);
DISPLAY INVISIBLE (-6800 10925);
FORCEPROP 1 LAST PART_NUMBER CS00002JB13
J 2
(-6875 10825);
DISPLAY 0.489362 (-6875 10825);
PAINT SKYBLUE (-6875 10825);
DISPLAY INVISIBLE (-6875 10825);
FORCEADD Q_RES..1
R 2
(-6850 10825);
FORCEPROP 1 LAST LOCATION R212
J 0
(-6600 10825);
DISPLAY 0.489362 (-6600 10825);
PAINT SKYBLUE (-6600 10825);
FORCEPROP 0 LAST $SEC 1
J 0
(-6600 10875);
DISPLAY 0.680851 (-6600 10875);
PAINT MONO (-6600 10875);
DISPLAY INVISIBLE (-6600 10875);
FORCEPROP 0 LAST CDS_SEC 1
J 0
(-6600 10875);
DISPLAY 1.021277 (-6600 10875);
DISPLAY INVISIBLE (-6600 10875);
FORCEPROP 1 LASTPIN (-6750 10825) $PN 1
J 2
(-6762 10837);
DISPLAY 0.489362 (-6762 10837);
PAINT MONO (-6762 10837);
FORCEPROP 1 LASTPIN (-6950 10825) $PN 2
J 2
(-6912 10837);
DISPLAY 0.489362 (-6912 10837);
PAINT MONO (-6912 10837);
FORCEPROP 1 LAST VALUE 33
J 0
(-6750 10825);
DISPLAY 0.489362 (-6750 10825);
PAINT SKYBLUE (-6750 10825);
FORCEPROP 1 LAST PACK_TYPE 0402LF
J 2
(-6900 10750);
DISPLAY 0.489362 (-6900 10750);
PAINT SKYBLUE (-6900 10750);
DISPLAY INVISIBLE (-6900 10750);
FORCEPROP 1 LAST TOLERANCE 5%
J 2
(-6825 10750);
DISPLAY 0.489362 (-6825 10750);
PAINT SKYBLUE (-6825 10750);
DISPLAY INVISIBLE (-6825 10750);
FORCEPROP 1 LAST MATERIAL CHIP
J 2
(-7275 10750);
DISPLAY 0.489362 (-7275 10750);
PAINT SKYBLUE (-7275 10750);
DISPLAY INVISIBLE (-7275 10750);
FORCEPROP 1 LAST WATTAGE 1/16W
J 0
(-7250 10750);
DISPLAY 0.489362 (-7250 10750);
PAINT SKYBLUE (-7250 10750);
DISPLAY INVISIBLE (-7250 10750);
FORCEPROP 2 LAST CDS_LIB pure_quanta
J 0
(-6850 10825);
DISPLAY INVISIBLE (-6850 10825);
FORCEPROP 1 LAST PATH I96
J 2
(-6800 10975);
DISPLAY 0.978723 (-6800 10975);
PAINT WHITE (-6800 10975);
DISPLAY INVISIBLE (-6800 10975);
FORCEPROP 1 LAST PART_NUMBER CS03302JB10
J 2
(-6875 10875);
DISPLAY 0.489362 (-6875 10875);
PAINT SKYBLUE (-6875 10875);
DISPLAY INVISIBLE (-6875 10875);
FORCEADD Q_RES..1
R 2
(-6850 10875);
FORCEPROP 1 LAST LOCATION R431
J 0
(-6600 10875);
DISPLAY 0.489362 (-6600 10875);
PAINT SKYBLUE (-6600 10875);
FORCEPROP 0 LAST $SEC 1
J 2
(-6575 10925);
DISPLAY 0.680851 (-6575 10925);
PAINT MONO (-6575 10925);
DISPLAY INVISIBLE (-6575 10925);
FORCEPROP 0 LAST CDS_SEC 1
J 2
(-6575 10925);
DISPLAY 1.021277 (-6575 10925);
DISPLAY INVISIBLE (-6575 10925);
FORCEPROP 1 LASTPIN (-6750 10875) $PN 1
J 2
(-6762 10887);
DISPLAY 0.489362 (-6762 10887);
PAINT MONO (-6762 10887);
FORCEPROP 1 LASTPIN (-6950 10875) $PN 2
J 2
(-6912 10887);
DISPLAY 0.489362 (-6912 10887);
PAINT MONO (-6912 10887);
FORCEPROP 1 LAST VALUE 0
J 0
(-6750 10875);
DISPLAY 0.489362 (-6750 10875);
PAINT SKYBLUE (-6750 10875);
FORCEPROP 1 LAST PACK_TYPE 0402LF
J 2
(-6900 10800);
DISPLAY 0.489362 (-6900 10800);
PAINT SKYBLUE (-6900 10800);
DISPLAY INVISIBLE (-6900 10800);
FORCEPROP 1 LAST TOLERANCE 5%
J 2
(-6825 10800);
DISPLAY 0.489362 (-6825 10800);
PAINT SKYBLUE (-6825 10800);
DISPLAY INVISIBLE (-6825 10800);
FORCEPROP 1 LAST MATERIAL CHIP
J 2
(-7275 10800);
DISPLAY 0.489362 (-7275 10800);
PAINT SKYBLUE (-7275 10800);
DISPLAY INVISIBLE (-7275 10800);
FORCEPROP 1 LAST WATTAGE 1/16W
J 0
(-7250 10800);
DISPLAY 0.489362 (-7250 10800);
PAINT SKYBLUE (-7250 10800);
DISPLAY INVISIBLE (-7250 10800);
FORCEPROP 2 LAST CDS_LIB pure_quanta
J 2
(-6850 10875);
DISPLAY INVISIBLE (-6850 10875);
FORCEPROP 1 LAST PATH I97
J 2
(-6800 11025);
DISPLAY 0.978723 (-6800 11025);
PAINT WHITE (-6800 11025);
DISPLAY INVISIBLE (-6800 11025);
FORCEPROP 1 LAST PART_NUMBER CS00002JB13
J 2
(-6875 10925);
DISPLAY 0.489362 (-6875 10925);
PAINT SKYBLUE (-6875 10925);
DISPLAY INVISIBLE (-6875 10925);
FORCEADD Q_RES..1
R 2
(-6850 10925);
FORCEPROP 1 LAST LOCATION R430
J 0
(-6600 10925);
DISPLAY 0.489362 (-6600 10925);
PAINT SKYBLUE (-6600 10925);
FORCEPROP 0 LAST $SEC 1
J 2
(-6575 10975);
DISPLAY 0.680851 (-6575 10975);
PAINT MONO (-6575 10975);
DISPLAY INVISIBLE (-6575 10975);
FORCEPROP 0 LAST CDS_SEC 1
J 2
(-6575 10975);
DISPLAY 1.021277 (-6575 10975);
DISPLAY INVISIBLE (-6575 10975);
FORCEPROP 1 LASTPIN (-6750 10925) $PN 1
J 2
(-6762 10937);
DISPLAY 0.489362 (-6762 10937);
PAINT MONO (-6762 10937);
FORCEPROP 1 LASTPIN (-6950 10925) $PN 2
J 2
(-6912 10937);
DISPLAY 0.489362 (-6912 10937);
PAINT MONO (-6912 10937);
FORCEPROP 1 LAST VALUE 0
J 0
(-6750 10925);
DISPLAY 0.489362 (-6750 10925);
PAINT SKYBLUE (-6750 10925);
FORCEPROP 1 LAST PACK_TYPE 0402LF
J 2
(-6900 10850);
DISPLAY 0.489362 (-6900 10850);
PAINT SKYBLUE (-6900 10850);
DISPLAY INVISIBLE (-6900 10850);
FORCEPROP 1 LAST TOLERANCE 5%
J 2
(-6825 10850);
DISPLAY 0.489362 (-6825 10850);
PAINT SKYBLUE (-6825 10850);
DISPLAY INVISIBLE (-6825 10850);
FORCEPROP 1 LAST MATERIAL CHIP
J 2
(-7275 10850);
DISPLAY 0.489362 (-7275 10850);
PAINT SKYBLUE (-7275 10850);
DISPLAY INVISIBLE (-7275 10850);
FORCEPROP 1 LAST WATTAGE 1/16W
J 0
(-7250 10850);
DISPLAY 0.489362 (-7250 10850);
PAINT SKYBLUE (-7250 10850);
DISPLAY INVISIBLE (-7250 10850);
FORCEPROP 2 LAST CDS_LIB pure_quanta
J 2
(-6850 10925);
DISPLAY INVISIBLE (-6850 10925);
FORCEPROP 1 LAST PATH I98
J 2
(-6800 11075);
DISPLAY 0.978723 (-6800 11075);
PAINT WHITE (-6800 11075);
DISPLAY INVISIBLE (-6800 11075);
FORCEPROP 1 LAST PART_NUMBER CS00002JB13
J 2
(-6875 10975);
DISPLAY 0.489362 (-6875 10975);
PAINT SKYBLUE (-6875 10975);
DISPLAY INVISIBLE (-6875 10975);
FORCEADD DNS..2
(-9100 9625);
PAINT RED (-9100 9625);
FORCEPROP 2 LAST BOM_COST OCP3.0 
J 0
(-9225 9750);
DISPLAY 0.680851 (-9225 9750);
DISPLAY INVISIBLE (-9225 9750);
FORCEPROP 2 LAST CDS_LIB mstr_misc
J 0
(-9100 9625);
DISPLAY INVISIBLE (-9100 9625);
FORCEPROP 1 LAST COMMENT_BODY TRUE
J 0
(-9100 9625);
DISPLAY 0.744681 (-9100 9625);
DISPLAY INVISIBLE (-9100 9625);
FORCEADD DNS..2
(-8900 9625);
PAINT RED (-8900 9625);
FORCEPROP 2 LAST BOM_COST OCP3.0 
J 0
(-9025 9750);
DISPLAY 0.680851 (-9025 9750);
DISPLAY INVISIBLE (-9025 9750);
FORCEPROP 2 LAST CDS_LIB mstr_misc
J 0
(-8900 9625);
DISPLAY INVISIBLE (-8900 9625);
FORCEPROP 1 LAST COMMENT_BODY TRUE
J 0
(-8900 9625);
DISPLAY 0.744681 (-8900 9625);
DISPLAY INVISIBLE (-8900 9625);
FORCEADD DNS..2
(-8725 9625);
PAINT RED (-8725 9625);
FORCEPROP 2 LAST BOM_COST OCP3.0 
J 0
(-8850 9750);
DISPLAY 0.680851 (-8850 9750);
DISPLAY INVISIBLE (-8850 9750);
FORCEPROP 2 LAST CDS_LIB mstr_misc
J 0
(-8725 9625);
DISPLAY INVISIBLE (-8725 9625);
FORCEPROP 1 LAST COMMENT_BODY TRUE
J 0
(-8725 9625);
DISPLAY 0.744681 (-8725 9625);
DISPLAY INVISIBLE (-8725 9625);
FORCEADD DNS..2
(-8550 9625);
PAINT RED (-8550 9625);
FORCEPROP 2 LAST BOM_COST OCP3.0 
J 0
(-8675 9750);
DISPLAY 0.680851 (-8675 9750);
DISPLAY INVISIBLE (-8675 9750);
FORCEPROP 2 LAST CDS_LIB mstr_misc
J 0
(-8550 9625);
DISPLAY INVISIBLE (-8550 9625);
FORCEPROP 1 LAST COMMENT_BODY TRUE
J 0
(-8550 9625);
DISPLAY 0.744681 (-8550 9625);
DISPLAY INVISIBLE (-8550 9625);
FORCEADD DESIGN_NOTE..1
(-8050 13250);
FORCEPROP 0 LAST L1 RST_SYS PU BY STRAP PIN
J 0
(-8250 13125);
DISPLAY 0.808511 (-8250 13125);
PAINT WHITE (-8250 13125);
FORCEPROP 2 LAST CDS_LIB pure_quanta_power
J 0
(-8050 13250);
DISPLAY INVISIBLE (-8050 13250);
FORCEPROP 1 LAST COMMENT_BODY TRUE
J 0
(-8025 13350);
DISPLAY 0.978723 (-8025 13350);
DISPLAY INVISIBLE (-8025 13350);
FORCEADD DNS..2
(-7775 8400);
PAINT RED (-7775 8400);
FORCEPROP 2 LAST CDS_LIB mstr_misc
J 0
(-7775 8400);
DISPLAY INVISIBLE (-7775 8400);
FORCEPROP 2 LAST BOM_COST OCP3.0 
J 0
(-7900 8525);
DISPLAY 0.680851 (-7900 8525);
DISPLAY INVISIBLE (-7900 8525);
FORCEPROP 1 LAST COMMENT_BODY TRUE
J 0
(-7775 8400);
DISPLAY 0.744681 (-7775 8400);
DISPLAY INVISIBLE (-7775 8400);
FORCEADD DNS..2
(-7850 7800);
PAINT RED (-7850 7800);
FORCEPROP 2 LAST BOM_COST OCP3.0 
J 0
(-7975 7925);
DISPLAY 0.680851 (-7975 7925);
DISPLAY INVISIBLE (-7975 7925);
FORCEPROP 2 LAST CDS_LIB mstr_misc
J 0
(-7850 7800);
DISPLAY INVISIBLE (-7850 7800);
FORCEPROP 1 LAST COMMENT_BODY TRUE
J 0
(-7850 7800);
DISPLAY 0.744681 (-7850 7800);
DISPLAY INVISIBLE (-7850 7800);
FORCEADD DNS..2
(-7175 7225);
PAINT RED (-7175 7225);
FORCEPROP 2 LAST BOM_COST OCP3.0 
J 0
(-7300 7350);
DISPLAY 0.680851 (-7300 7350);
DISPLAY INVISIBLE (-7300 7350);
FORCEPROP 2 LAST CDS_LIB mstr_misc
J 0
(-7175 7225);
DISPLAY INVISIBLE (-7175 7225);
FORCEPROP 1 LAST COMMENT_BODY TRUE
J 0
(-7175 7225);
DISPLAY 0.744681 (-7175 7225);
DISPLAY INVISIBLE (-7175 7225);
FORCEADD DNS..2
(-7375 7750);
PAINT RED (-7375 7750);
FORCEPROP 2 LAST CDS_LIB mstr_misc
J 0
(-7375 7750);
DISPLAY INVISIBLE (-7375 7750);
FORCEPROP 2 LAST BOM_COST OCP3.0 
J 0
(-7500 7875);
DISPLAY 0.680851 (-7500 7875);
DISPLAY INVISIBLE (-7500 7875);
FORCEPROP 1 LAST COMMENT_BODY TRUE
J 0
(-7375 7750);
DISPLAY 0.744681 (-7375 7750);
DISPLAY INVISIBLE (-7375 7750);
FORCEADD DNS..2
(-7025 7225);
PAINT RED (-7025 7225);
FORCEPROP 2 LAST CDS_LIB mstr_misc
J 0
(-7025 7225);
DISPLAY INVISIBLE (-7025 7225);
FORCEPROP 2 LAST BOM_COST OCP3.0 
J 0
(-7150 7350);
DISPLAY 0.680851 (-7150 7350);
DISPLAY INVISIBLE (-7150 7350);
FORCEPROP 1 LAST COMMENT_BODY TRUE
J 0
(-7025 7225);
DISPLAY 0.744681 (-7025 7225);
DISPLAY INVISIBLE (-7025 7225);
FORCEADD DNS..2
(-6875 7225);
PAINT RED (-6875 7225);
FORCEPROP 2 LAST CDS_LIB mstr_misc
J 0
(-6875 7225);
DISPLAY INVISIBLE (-6875 7225);
FORCEPROP 2 LAST BOM_COST OCP3.0 
J 0
(-7000 7350);
DISPLAY 0.680851 (-7000 7350);
DISPLAY INVISIBLE (-7000 7350);
FORCEPROP 1 LAST COMMENT_BODY TRUE
J 0
(-6875 7225);
DISPLAY 0.744681 (-6875 7225);
DISPLAY INVISIBLE (-6875 7225);
FORCEADD DNS..2
(-6725 7225);
PAINT RED (-6725 7225);
FORCEPROP 2 LAST CDS_LIB mstr_misc
J 0
(-6725 7225);
DISPLAY INVISIBLE (-6725 7225);
FORCEPROP 2 LAST BOM_COST OCP3.0 
J 0
(-6850 7350);
DISPLAY 0.680851 (-6850 7350);
DISPLAY INVISIBLE (-6850 7350);
FORCEPROP 1 LAST COMMENT_BODY TRUE
J 0
(-6725 7225);
DISPLAY 0.744681 (-6725 7225);
DISPLAY INVISIBLE (-6725 7225);
FORCEADD DNS..2
(-7775 8875);
PAINT RED (-7775 8875);
FORCEPROP 2 LAST CDS_LIB mstr_misc
J 0
(-7775 8875);
DISPLAY INVISIBLE (-7775 8875);
FORCEPROP 2 LAST BOM_COST OCP3.0 
J 0
(-7900 9000);
DISPLAY 0.680851 (-7900 9000);
DISPLAY INVISIBLE (-7900 9000);
FORCEPROP 1 LAST COMMENT_BODY TRUE
J 0
(-7775 8875);
DISPLAY 0.744681 (-7775 8875);
DISPLAY INVISIBLE (-7775 8875);
FORCEADD QUANTA_TITLE_BLOCK_C..1
(25 6850);
FORCEPROP 0 LAST CDS_CON_LAST_MODIFIED Thu Sep 14 16:12:37 2023
J 0
(-1860 6865);
DISPLAY INVISIBLE (-1860 6865);
FORCEPROP 1 LAST CUSTOM_TXT_CDS <CON_LAST_MODIFIED>
J 0
(-1860 6865);
DISPLAY 0.978723 (-1860 6865);
FORCEPROP 2 LAST CUSTOM_TXT_CDS <XR_PAGE_TITLE>
J 0
(-7865 12100);
DISPLAY 0.638298 (-7865 12100);
PAINT PINK (-7865 12100);
DISPLAY INVISIBLE (-7865 12100);
FORCEPROP 1 LAST CUSTOM_TXT_CDS <NAME_2>
J 0
(-3150 6900);
FORCEPROP 1 LAST CUSTOM_TXT_CDS <NAME_1>
J 0
(-3150 7025);
FORCEPROP 1 LAST CUSTOM_TXT_CDS <Q_NUMBER>
J 0
(-1378 6953);
DISPLAY 1.212766 (-1378 6953);
FORCEPROP 1 LAST CUSTOM_TXT_CDS <Q_PROJ>
J 0
(-2357 6952);
DISPLAY 1.212766 (-2357 6952);
FORCEPROP 1 LAST CUSTOM_TXT_CDS <Q_REV>
J 0
(-159 6953);
DISPLAY 1.212766 (-159 6953);
FORCEPROP 1 LAST CUSTOM_TXT_CDS <CON_PAGE_NUM> OF <CON_TOTAL_PAGES>
J 0
(-421 6868);
DISPLAY 0.978723 (-421 6868);
FORCEPROP 1 LAST Q_TITLE CPU0 MISC 2/2
J 0
(-9275 6900);
DISPLAY 2.446809 (-9275 6900);
PAINT GREEN (-9275 6900);
FORCEPROP 2 LAST PAGE_BORDER TRUE
J 0
(-7865 12100);
DISPLAY 0.638298 (-7865 12100);
PAINT PINK (-7865 12100);
DISPLAY INVISIBLE (-7865 12100);
FORCEPROP 1 LAST CDS_LMAN_SYM_OUTLINE -9475,6775,100,-125
J 0
(25 6850);
DISPLAY 0.468085 (25 6850);
PAINT GREEN (25 6850);
DISPLAY INVISIBLE (25 6850);
FORCEPROP 2 LAST CDS_LIB pure_quanta
J 0
(25 6850);
DISPLAY INVISIBLE (25 6850);
FORCEPROP 2 LAST CDS_XR_PAGE_TITLE CR-28 : @T6G_MB_LIB.T6G(SCH_1):PAGE28
J 0
(-7865 12100);
DISPLAY 0.638298 (-7865 12100);
PAINT PINK (-7865 12100);
DISPLAY INVISIBLE (-7865 12100);
FORCEPROP 1 LAST Q_DEPT BU9
J 1
(-3738 6899);
DISPLAY 1.957447 (-3738 6899);
PAINT GREEN (-3738 6899);
DISPLAY INVISIBLE (-3738 6899);
FORCEPROP 1 LAST COMMENT_BODY TRUE
J 0
(37 6837);
DISPLAY 0.978723 (37 6837);
PAINT GREEN (37 6837);
DISPLAY INVISIBLE (37 6837);
FORCEADD DNS..2
(-7350 7200);
PAINT RED (-7350 7200);
FORCEPROP 2 LAST BOM_COST OCP3.0 
J 0
(-7475 7325);
DISPLAY 0.680851 (-7475 7325);
DISPLAY INVISIBLE (-7475 7325);
FORCEPROP 2 LAST CDS_LIB mstr_misc
J 0
(-7350 7200);
DISPLAY INVISIBLE (-7350 7200);
FORCEPROP 1 LAST COMMENT_BODY TRUE
J 0
(-7350 7200);
DISPLAY 0.744681 (-7350 7200);
DISPLAY INVISIBLE (-7350 7200);
FORCEADD DNS..2
(-7575 7225);
PAINT RED (-7575 7225);
FORCEPROP 2 LAST CDS_LIB mstr_misc
J 0
(-7575 7225);
DISPLAY INVISIBLE (-7575 7225);
FORCEPROP 2 LAST BOM_COST OCP3.0 
J 0
(-7700 7350);
DISPLAY 0.680851 (-7700 7350);
DISPLAY INVISIBLE (-7700 7350);
FORCEPROP 1 LAST COMMENT_BODY TRUE
J 0
(-7575 7225);
DISPLAY 0.744681 (-7575 7225);
DISPLAY INVISIBLE (-7575 7225);
FORCEADD DNS..2
(-7825 7225);
PAINT RED (-7825 7225);
FORCEPROP 2 LAST CDS_LIB mstr_misc
J 0
(-7825 7225);
DISPLAY INVISIBLE (-7825 7225);
FORCEPROP 2 LAST BOM_COST OCP3.0 
J 0
(-7950 7350);
DISPLAY 0.680851 (-7950 7350);
DISPLAY INVISIBLE (-7950 7350);
FORCEPROP 1 LAST COMMENT_BODY TRUE
J 0
(-7825 7225);
DISPLAY 0.744681 (-7825 7225);
DISPLAY INVISIBLE (-7825 7225);
WIRE 16 -1 (-5850 8525)(-5950 8525);
WIRE 16 -1 (-5950 8525)(-5950 8375);
WIRE 16 -1 (-5300 8525)(-5150 8525);
WIRE 16 -1 (-5150 8525)(-5150 8350);
WIRE 16 -1 (-4950 7800)(-4950 7650);
WIRE 16 -1 (-3900 7775)(-3900 7950);
WIRE 16 -1 (-2800 7775)(-2800 7975);
WIRE 16 -1 (-7125 12150)(-7125 12100);
WIRE 16 -1 (-6350 8575)(-6350 8275);
WIRE 16 -1 (-6225 7800)(-6225 7650);
WIRE 16 -1 (-6775 7850)(-6775 7900);
WIRE 16 -1 (-6775 7900)(-6925 7900);
WIRE 16 -1 (-6925 7850)(-6925 7900);
WIRE 16 -1 (-6925 7900)(-7075 7900);
WIRE 16 -1 (-7075 7850)(-7075 7900);
WIRE 16 -1 (-7075 7900)(-7225 7900);
WIRE 16 -1 (-7225 7850)(-7225 7900);
WIRE 16 -1 (-7400 7900)(-7225 7900);
WIRE 16 -1 (-7400 7950)(-7400 7900);
WIRE 16 -1 (-7400 7900)(-7400 7850);
WIRE 16 -1 (-7625 7900)(-7400 7900);
WIRE 16 -1 (-7625 7850)(-7625 7900);
WIRE 16 -1 (-7900 7900)(-7625 7900);
WIRE 16 -1 (-7900 7875)(-7900 7900);
WIRE 16 -1 (-7075 7650)(-7075 7450);
WIRE 16 -1 (-7075 7450)(-7075 7325);
WIRE 16 -1 (-8725 7450)(-7075 7450);
FORCEPROP 2 LAST SIG_NAME IRQ_SMI_ACTIVE_N
J 0
(-8625 7460);
DISPLAY 0.553191 (-8625 7460);
WIRE 16 -1 (-8725 7400)(-6925 7400);
FORCEPROP 2 LAST SIG_NAME IRQ_BMC_SMI_N
J 0
(-8625 7410);
DISPLAY 0.553191 (-8625 7410);
WIRE 16 -1 (-6925 7650)(-6925 7400);
WIRE 16 -1 (-6925 7400)(-6925 7325);
WIRE 16 -1 (-6775 7650)(-6775 7350);
WIRE 16 -1 (-6775 7350)(-6775 7325);
WIRE 16 -1 (-6775 7350)(-8725 7350);
FORCEPROP 2 LAST SIG_NAME IRQ_TPM_SPI_R_N
J 0
(-8625 7360);
DISPLAY 0.553191 (-8625 7360);
WIRE 16 -1 (-7250 9625)(-5600 9625);
FORCEPROP 2 LAST SIG_NAME FM_BOARD_SKU_ID4
J 0
(-7225 9635);
DISPLAY 0.489362 (-7225 9635);
WIRE 16 -1 (-5600 9675)(-7250 9675);
FORCEPROP 2 LAST SIG_NAME CPU0_ROM_TYPE_SELECT
J 0
(-7225 9685);
DISPLAY 0.489362 (-7225 9685);
WIRE 16 -1 (-7250 9725)(-5600 9725);
FORCEPROP 2 LAST SIG_NAME FM_BOARD_SKU_ID3
J 0
(-7225 9735);
DISPLAY 0.489362 (-7225 9735);
WIRE 16 -1 (-7250 9775)(-5600 9775);
FORCEPROP 2 LAST SIG_NAME FM_BOARD_SKU_ID2
J 0
(-7225 9785);
DISPLAY 0.489362 (-7225 9785);
WIRE 16 -1 (-7250 9825)(-5600 9825);
FORCEPROP 2 LAST SIG_NAME BIOS_DEBUG_MODE
J 0
(-7225 9835);
DISPLAY 0.489362 (-7225 9835);
WIRE 16 -1 (-5600 9875)(-6275 9875);
FORCEPROP 2 LAST SIG_NAME BOOT_RDY_R_H
J 0
(-6185 9885);
DISPLAY 0.489362 (-6185 9885);
FORCEPROP 2 LASTPROP $XRERR UNIQUE?
J 0
(-6425 9885);
DISPLAY 0.638298 (-6425 9885);
PAINT MONO (-6425 9885);
DISPLAY INVISIBLE (-6425 9885);
WIRE 16 -1 (-5600 9925)(-6275 9925);
FORCEPROP 2 LAST SIG_NAME FM_BIOS_POST_CMPLT_R_N
J 0
(-6185 9935);
DISPLAY 0.489362 (-6185 9935);
FORCEPROP 2 LASTPROP $XRERR UNIQUE?
J 0
(-6425 9935);
DISPLAY 0.638298 (-6425 9935);
PAINT MONO (-6425 9935);
DISPLAY INVISIBLE (-6425 9935);
WIRE 16 -1 (-7250 10025)(-5600 10025);
FORCEPROP 2 LAST SIG_NAME FM_BOARD_SKU_ID1
J 0
(-7225 10035);
DISPLAY 0.489362 (-7225 10035);
WIRE 16 -1 (-5300 8725)(-4950 8725);
FORCEPROP 2 LAST SIG_NAME XTAL_CPU0_X48M_X2_R
J 0
(-5210 8735);
DISPLAY 0.489362 (-5210 8735);
FORCEPROP 2 LASTPROP $XRERR UNIQUE?
J 0
(-5450 8735);
DISPLAY 0.638298 (-5450 8735);
PAINT MONO (-5450 8735);
DISPLAY INVISIBLE (-5450 8735);
WIRE 16 -1 (-4950 8725)(-4950 8825);
WIRE 16 -1 (-4950 8725)(-4950 8125);
WIRE 16 -1 (-4950 8125)(-4950 8000);
WIRE 16 -1 (-5475 8125)(-4950 8125);
WIRE 16 -1 (-5850 8725)(-6225 8725);
WIRE 16 -1 (-6225 8725)(-6225 9175);
WIRE 16 -1 (-6225 8725)(-6225 8125);
WIRE 16 -1 (-5675 8125)(-6225 8125);
WIRE 16 -1 (-6225 8125)(-6225 8000);
WIRE 16 -1 (-6225 9175)(-4600 9175);
FORCEPROP 2 LAST SIG_NAME XTAL_CPU0_X48M_X1
J 0
(-4985 9185);
DISPLAY 0.489362 (-4985 9185);
WIRE 16 -1 (-6975 8900)(-6350 8900);
FORCEPROP 2 LAST SIG_NAME CPU0_FORCE_SELFREFRESH
J 0
(-6960 8910);
DISPLAY 0.553191 (-6960 8910);
WIRE 16 -1 (-6350 8775)(-6350 8900);
WIRE 16 -1 (-5600 10825)(-6750 10825);
FORCEPROP 2 LAST SIG_NAME SMB_CPU_5_R_SCL
J 0
(-6400 10835);
DISPLAY 0.489362 (-6400 10835);
FORCEPROP 2 LASTPROP $XRERR UNIQUE?
J 0
(-6640 10835);
DISPLAY 0.638298 (-6640 10835);
PAINT MONO (-6640 10835);
DISPLAY INVISIBLE (-6640 10835);
WIRE 16 -1 (-7850 10825)(-6950 10825);
FORCEPROP 2 LAST SIG_NAME SMB_CPU_5_SCL
J 0
(-7725 10835);
DISPLAY 0.489362 (-7725 10835);
WIRE 16 -1 (-1900 10875)(-650 10875);
FORCEPROP 2 LAST SIG_NAME CLK_100M_CPU0_CLK12_DN
J 0
(-1360 10885);
DISPLAY 0.489362 (-1360 10885);
WIRE 16 -1 (-1900 10725)(-650 10725);
FORCEPROP 2 LAST SIG_NAME CLK_100M_CPU0_CLK13_DN
J 0
(-1385 10735);
DISPLAY 0.553191 (-1385 10735);
WIRE 16 -1 (-1900 10925)(-650 10925);
FORCEPROP 2 LAST SIG_NAME CLK_100M_CPU0_CLK12_DP
J 0
(-1360 10935);
DISPLAY 0.489362 (-1360 10935);
WIRE 16 -1 (-1875 11175)(-650 11175);
FORCEPROP 2 LAST SIG_NAME CLK_100M_CPU0_CLK05_DN
J 0
(-1360 11185);
DISPLAY 0.489362 (-1360 11185);
WIRE 16 -1 (-1875 11225)(-650 11225);
FORCEPROP 2 LAST SIG_NAME CLK_100M_CPU0_CLK05_DP
J 0
(-1360 11235);
DISPLAY 0.489362 (-1360 11235);
WIRE 16 -1 (-1900 11325)(-650 11325);
FORCEPROP 2 LAST SIG_NAME CLK_100M_CPU0_CLK04_DN
J 0
(-1360 11335);
DISPLAY 0.489362 (-1360 11335);
WIRE 16 -1 (-1900 11075)(-650 11075);
FORCEPROP 2 LAST SIG_NAME CLK_100M_CPU0_CLK11_DP
J 0
(-1360 11085);
DISPLAY 0.489362 (-1360 11085);
WIRE 16 -1 (-1900 11025)(-650 11025);
FORCEPROP 2 LAST SIG_NAME CLK_100M_CPU0_CLK11_DN
J 0
(-1360 11035);
DISPLAY 0.489362 (-1360 11035);
WIRE 16 -1 (-2100 10925)(-3100 10925);
FORCEPROP 2 LAST SIG_NAME CLK_100M_CPU0_CLK12_R_DP
J 0
(-2960 10925);
DISPLAY 0.489362 (-2960 10925);
FORCEPROP 2 LASTPROP $XRERR UNIQUE?
J 0
(-3200 10925);
DISPLAY 0.638298 (-3200 10925);
PAINT MONO (-3200 10925);
DISPLAY INVISIBLE (-3200 10925);
WIRE 16 -1 (-3100 11325)(-2100 11325);
FORCEPROP 2 LAST SIG_NAME CLK_100M_CPU0_CLK04_R_DN
J 0
(-2960 11325);
DISPLAY 0.489362 (-2960 11325);
FORCEPROP 2 LASTPROP $XRERR UNIQUE?
J 0
(-3200 11325);
DISPLAY 0.638298 (-3200 11325);
PAINT MONO (-3200 11325);
DISPLAY INVISIBLE (-3200 11325);
WIRE 16 -1 (-2100 10775)(-3100 10775);
FORCEPROP 2 LAST SIG_NAME CLK_100M_CPU0_CLK13_R_DP
J 0
(-2985 10785);
DISPLAY 0.553191 (-2985 10785);
FORCEPROP 2 LASTPROP $XRERR UNIQUE?
J 0
(-3225 10785);
DISPLAY 0.638298 (-3225 10785);
PAINT MONO (-3225 10785);
DISPLAY INVISIBLE (-3225 10785);
WIRE 16 -1 (-2100 10725)(-3100 10725);
FORCEPROP 0 LAST SIG_NAME CLK_100M_CPU0_CLK13_R_DN
J 0
(-2985 10735);
DISPLAY 0.553191 (-2985 10735);
FORCEPROP 2 LASTPROP $XRERR UNIQUE?
J 0
(-3225 10735);
DISPLAY 0.638298 (-3225 10735);
PAINT MONO (-3225 10735);
DISPLAY INVISIBLE (-3225 10735);
WIRE 16 -1 (-2100 10875)(-3100 10875);
FORCEPROP 2 LAST SIG_NAME CLK_100M_CPU0_CLK12_R_DN
J 0
(-2960 10875);
DISPLAY 0.489362 (-2960 10875);
FORCEPROP 2 LASTPROP $XRERR UNIQUE?
J 0
(-3200 10875);
DISPLAY 0.638298 (-3200 10875);
PAINT MONO (-3200 10875);
DISPLAY INVISIBLE (-3200 10875);
WIRE 16 -1 (-3100 11225)(-2075 11225);
FORCEPROP 2 LAST SIG_NAME CLK_100M_CPU0_CLK05_R_DP
J 0
(-2960 11225);
DISPLAY 0.489362 (-2960 11225);
FORCEPROP 2 LASTPROP $XRERR UNIQUE?
J 0
(-3200 11225);
DISPLAY 0.638298 (-3200 11225);
PAINT MONO (-3200 11225);
DISPLAY INVISIBLE (-3200 11225);
WIRE 16 -1 (-1900 11525)(-650 11525);
FORCEPROP 2 LAST SIG_NAME CLK_100M_CPU0_CLK03_DP
J 0
(-1360 11535);
DISPLAY 0.489362 (-1360 11535);
WIRE 16 -1 (-3100 10075)(-2175 10075);
FORCEPROP 2 LAST SIG_NAME SMB_CPU0_SEC_SCL
J 0
(-2725 10085);
DISPLAY 0.489362 (-2725 10085);
WIRE 16 -1 (-7675 8975)(-7425 8975);
WIRE 16 -1 (-7425 9025)(-7425 8975);
WIRE 16 -1 (-7425 8975)(-7425 8925);
WIRE 16 -1 (-7425 8775)(-7425 8925);
WIRE 16 -1 (-7675 8925)(-7425 8925);
WIRE 16 -1 (-7425 8725)(-7425 8775);
WIRE 16 -1 (-7675 8775)(-7425 8775);
WIRE 16 -1 (-7675 8725)(-7425 8725);
WIRE 16 -1 (-7425 8675)(-7425 8725);
WIRE 16 -1 (-7675 8675)(-7425 8675);
WIRE 16 -1 (-7425 8675)(-7425 8425);
WIRE 16 -1 (-7425 8375)(-7425 8425);
WIRE 16 -1 (-7675 8425)(-7425 8425);
WIRE 16 -1 (-7425 8325)(-7425 8375);
WIRE 16 -1 (-7675 8375)(-7425 8375);
WIRE 16 -1 (-7425 8275)(-7425 8325);
WIRE 16 -1 (-7675 8325)(-7425 8325);
WIRE 16 -1 (-7425 8225)(-7425 8275);
WIRE 16 -1 (-7675 8275)(-7425 8275);
WIRE 16 -1 (-7675 8225)(-7425 8225);
WIRE 16 -1 (-7425 8175)(-7425 8225);
WIRE 16 -1 (-7675 8175)(-7425 8175);
WIRE 16 -1 (-8600 13150)(-8600 13200);
WIRE 16 -1 (-8600 13300)(-8600 13200);
WIRE 16 -1 (-8600 13200)(-8775 13200);
WIRE 16 -1 (-8775 13150)(-8775 13200);
WIRE 16 -1 (-9025 12325)(-9125 12325);
WIRE 16 -1 (-9125 12325)(-9125 12225);
WIRE 16 -1 (-9025 12225)(-9125 12225);
WIRE 16 -1 (-9125 12225)(-9125 12125);
WIRE 16 -1 (-9025 12125)(-9125 12125);
WIRE 16 -1 (-9125 12125)(-9125 12000);
WIRE 16 -1 (-8575 9750)(-8575 9800);
WIRE 16 -1 (-8575 9900)(-8575 9800);
WIRE 16 -1 (-8575 9800)(-8750 9800);
WIRE 16 -1 (-8750 9750)(-8750 9800);
WIRE 16 -1 (-8750 9800)(-8925 9800);
WIRE 16 -1 (-8925 9750)(-8925 9800);
WIRE 16 -1 (-8925 9800)(-9100 9800);
WIRE 16 -1 (-9100 9750)(-9100 9800);
WIRE 16 -1 (-8475 11075)(-8375 11075);
WIRE 16 -1 (-8475 11075)(-8475 11125);
WIRE 16 -1 (-8475 11025)(-8475 11075);
WIRE 16 -1 (-8475 11025)(-8375 11025);
WIRE 16 -1 (-8475 10975)(-8475 11025);
WIRE 16 -1 (-8475 11125)(-8475 11325);
WIRE 16 -1 (-8475 11125)(-8375 11125);
WIRE 16 -1 (-8475 10975)(-8375 10975);
WIRE 16 -1 (-2100 11025)(-3100 11025);
FORCEPROP 2 LAST SIG_NAME CLK_100M_CPU0_CLK11_R_DN
J 0
(-2960 11025);
DISPLAY 0.489362 (-2960 11025);
FORCEPROP 2 LASTPROP $XRERR UNIQUE?
J 0
(-3200 11025);
DISPLAY 0.638298 (-3200 11025);
PAINT MONO (-3200 11025);
DISPLAY INVISIBLE (-3200 11025);
WIRE 16 -1 (-2100 11075)(-3100 11075);
FORCEPROP 2 LAST SIG_NAME CLK_100M_CPU0_CLK11_R_DP
J 0
(-2960 11075);
DISPLAY 0.489362 (-2960 11075);
FORCEPROP 2 LASTPROP $XRERR UNIQUE?
J 0
(-3200 11075);
DISPLAY 0.638298 (-3200 11075);
PAINT MONO (-3200 11075);
DISPLAY INVISIBLE (-3200 11075);
WIRE 16 -1 (-1925 11675)(-650 11675);
FORCEPROP 2 LAST SIG_NAME CLK_100M_CPU0_CLK02_DP
J 0
(-1360 11685);
DISPLAY 0.489362 (-1360 11685);
WIRE 16 -1 (-1900 11375)(-650 11375);
FORCEPROP 2 LAST SIG_NAME CLK_100M_CPU0_CLK04_DP
J 0
(-1360 11385);
DISPLAY 0.489362 (-1360 11385);
WIRE 16 -1 (-5600 11775)(-7850 11775);
FORCEPROP 2 LAST SIG_NAME FM_INT_CPU0_HP_UBM_N
J 2
(-7235 11785);
DISPLAY 0.489362 (-7235 11785);
WIRE 16 -1 (-4950 9025)(-4950 9125);
FORCEPROP 2 LAST SIG_NAME XTAL_CPU0_X48M_X2
J 0
(-4985 9135);
DISPLAY 0.489362 (-4985 9135);
WIRE 16 -1 (-4950 9125)(-4600 9125);
WIRE 16 -1 (-7875 8225)(-8700 8225);
FORCEPROP 2 LAST SIG_NAME CPU0_NV_SAVE_N
J 0
(-8585 8235);
DISPLAY 0.489362 (-8585 8235);
WIRE 16 -1 (-7875 8275)(-8700 8275);
FORCEPROP 2 LAST SIG_NAME CPU0_SPD_HOST_CTRL_N
J 2
(-8135 8285);
DISPLAY 0.489362 (-8135 8285);
WIRE 16 -1 (-7875 8325)(-8700 8325);
FORCEPROP 2 LAST SIG_NAME CPU0_SMERR_N
J 0
(-8585 8335);
DISPLAY 0.489362 (-8585 8335);
WIRE 16 -1 (-7875 8775)(-8700 8775);
FORCEPROP 2 LAST SIG_NAME CPU0_NMI_SYNC_FLOOD_N
J 0
(-8585 8785);
DISPLAY 0.489362 (-8585 8785);
WIRE 16 -1 (-7875 8675)(-8700 8675);
FORCEPROP 2 LAST SIG_NAME PWRGD_CPU0_PWROK
J 0
(-8585 8685);
DISPLAY 0.489362 (-8585 8685);
WIRE 16 -1 (-7875 8725)(-8700 8725);
FORCEPROP 2 LAST SIG_NAME RST_CPU0_RESETL_N
J 0
(-8585 8735);
DISPLAY 0.489362 (-8585 8735);
WIRE 16 -1 (-7225 7650)(-7225 7500);
WIRE 16 -1 (-7225 7325)(-7225 7500);
WIRE 16 -1 (-7225 7500)(-8725 7500);
FORCEPROP 2 LAST SIG_NAME FM_SMM_CRASHDUMP
J 0
(-8625 7510);
DISPLAY 0.553191 (-8625 7510);
WIRE 16 -1 (-7400 7550)(-7400 7650);
WIRE 16 -1 (-7400 7325)(-7400 7550);
WIRE 16 -1 (-7400 7550)(-8725 7550);
FORCEPROP 2 LAST SIG_NAME CPU0_PWR_GD_OUT
J 0
(-8625 7560);
DISPLAY 0.489362 (-8625 7560);
WIRE 16 -1 (-7875 8375)(-8700 8375);
FORCEPROP 2 LAST SIG_NAME CPU0_SLP_S3_N
J 0
(-8585 8385);
DISPLAY 0.489362 (-8585 8385);
WIRE 16 -1 (-7875 8425)(-8700 8425);
FORCEPROP 2 LAST SIG_NAME CPU0_SLP_S5_N
J 0
(-8585 8435);
DISPLAY 0.489362 (-8585 8435);
WIRE 16 -1 (-7900 7675)(-7900 7650);
WIRE 16 -1 (-7900 7650)(-7900 7325);
WIRE 16 -1 (-7900 7650)(-8725 7650);
FORCEPROP 2 LAST SIG_NAME RST_CPU0_RSMRST_N
J 0
(-8625 7660);
DISPLAY 0.489362 (-8625 7660);
WIRE 16 -1 (-8725 7600)(-7625 7600);
FORCEPROP 2 LAST SIG_NAME CPU0_PWR_GOOD
J 0
(-8625 7610);
DISPLAY 0.489362 (-8625 7610);
WIRE 16 -1 (-7625 7600)(-7625 7650);
WIRE 16 -1 (-7625 7325)(-7625 7600);
WIRE 16 -1 (-7875 8175)(-8700 8175);
FORCEPROP 2 LAST SIG_NAME FM_INT_CPU0_HP_UBM_N
J 2
(-8135 8185);
DISPLAY 0.489362 (-8135 8185);
WIRE 16 -1 (-3100 12025)(-2300 12025);
FORCEPROP 2 LAST SIG_NAME RST_CPU0_PERST1_N
J 0
(-2935 12035);
DISPLAY 0.489362 (-2935 12035);
WIRE 16 -1 (-3100 11825)(-2125 11825);
FORCEPROP 2 LAST SIG_NAME CLK_100M_CPU0_CLK01_R_DP
J 0
(-2960 11825);
DISPLAY 0.489362 (-2960 11825);
FORCEPROP 2 LASTPROP $XRERR UNIQUE?
J 0
(-3200 11825);
DISPLAY 0.638298 (-3200 11825);
PAINT MONO (-3200 11825);
DISPLAY INVISIBLE (-3200 11825);
WIRE 16 -1 (-650 12425)(-3100 12425);
FORCEPROP 2 LAST SIG_NAME IRQ_WAKE_N
J 0
(-2910 12435);
DISPLAY 0.489362 (-2910 12435);
WIRE 16 -1 (-3100 12075)(-2300 12075);
FORCEPROP 2 LAST SIG_NAME RST_CPU0_PERST0_N
J 0
(-2935 12085);
DISPLAY 0.489362 (-2935 12085);
WIRE 16 -1 (-5600 10175)(-7250 10175);
FORCEPROP 2 LAST SIG_NAME IRQ_SMI_ACTIVE_N
J 0
(-7225 10185);
DISPLAY 0.489362 (-7225 10185);
WIRE 16 -1 (-3100 9775)(-2175 9775);
FORCEPROP 2 LAST SIG_NAME FAB_REV_ID2
J 0
(-2725 9785);
DISPLAY 0.489362 (-2725 9785);
WIRE 16 -1 (-3100 9825)(-2175 9825);
FORCEPROP 2 LAST SIG_NAME FAB_REV_ID1
J 0
(-2725 9835);
DISPLAY 0.489362 (-2725 9835);
WIRE 16 -1 (-3100 9875)(-2175 9875);
FORCEPROP 2 LAST SIG_NAME FAB_REV_ID0
J 0
(-2725 9885);
DISPLAY 0.489362 (-2725 9885);
WIRE 16 -1 (-3100 10025)(-2175 10025);
FORCEPROP 2 LAST SIG_NAME SMB_CPU0_SEC_SDA
J 0
(-2725 10035);
DISPLAY 0.489362 (-2725 10035);
WIRE 16 -1 (-5600 11575)(-6650 11575);
FORCEPROP 2 LAST SIG_NAME CPU0_NMI_SYNC_FLOOD_N
J 0
(-6535 11585);
DISPLAY 0.489362 (-6535 11585);
WIRE 16 -1 (-7250 9875)(-6475 9875);
FORCEPROP 2 LAST SIG_NAME BOOT_RDY_H
J 0
(-7225 9885);
DISPLAY 0.489362 (-7225 9885);
WIRE 16 -1 (-7875 12325)(-8475 12325);
FORCEPROP 2 LAST SIG_NAME CPU0_PWR_BTN_N
J 0
(-8400 12335);
DISPLAY 0.489362 (-8400 12335);
WIRE 16 -1 (-5600 12475)(-6325 12475);
FORCEPROP 2 LAST SIG_NAME RST_CPU0_SYS_N
J 0
(-6250 12485);
DISPLAY 0.489362 (-6250 12485);
WIRE 16 -1 (-3100 11675)(-2125 11675);
FORCEPROP 2 LAST SIG_NAME CLK_100M_CPU0_CLK02_R_DP
J 0
(-2960 11675);
DISPLAY 0.489362 (-2960 11675);
FORCEPROP 2 LASTPROP $XRERR UNIQUE?
J 0
(-3200 11675);
DISPLAY 0.638298 (-3200 11675);
PAINT MONO (-3200 11675);
DISPLAY INVISIBLE (-3200 11675);
WIRE 16 -1 (-3100 11375)(-2100 11375);
FORCEPROP 2 LAST SIG_NAME CLK_100M_CPU0_CLK04_R_DP
J 0
(-2960 11375);
DISPLAY 0.489362 (-2960 11375);
FORCEPROP 2 LASTPROP $XRERR UNIQUE?
J 0
(-3200 11375);
DISPLAY 0.638298 (-3200 11375);
PAINT MONO (-3200 11375);
DISPLAY INVISIBLE (-3200 11375);
WIRE 16 -1 (-3100 11475)(-2100 11475);
FORCEPROP 2 LAST SIG_NAME CLK_100M_CPU0_CLK03_R_DN
J 0
(-2960 11475);
DISPLAY 0.489362 (-2960 11475);
FORCEPROP 2 LASTPROP $XRERR UNIQUE?
J 0
(-3200 11475);
DISPLAY 0.638298 (-3200 11475);
PAINT MONO (-3200 11475);
DISPLAY INVISIBLE (-3200 11475);
WIRE 16 -1 (-3100 11775)(-2125 11775);
FORCEPROP 2 LAST SIG_NAME CLK_100M_CPU0_CLK01_R_DN
J 0
(-2960 11775);
DISPLAY 0.489362 (-2960 11775);
FORCEPROP 2 LASTPROP $XRERR UNIQUE?
J 0
(-3200 11775);
DISPLAY 0.638298 (-3200 11775);
PAINT MONO (-3200 11775);
DISPLAY INVISIBLE (-3200 11775);
WIRE 16 -1 (-3100 11525)(-2100 11525);
FORCEPROP 2 LAST SIG_NAME CLK_100M_CPU0_CLK03_R_DP
J 0
(-2960 11525);
DISPLAY 0.489362 (-2960 11525);
FORCEPROP 2 LASTPROP $XRERR UNIQUE?
J 0
(-3200 11525);
DISPLAY 0.638298 (-3200 11525);
PAINT MONO (-3200 11525);
DISPLAY INVISIBLE (-3200 11525);
WIRE 16 -1 (-3100 11175)(-2075 11175);
FORCEPROP 2 LAST SIG_NAME CLK_100M_CPU0_CLK05_R_DN
J 0
(-2960 11175);
DISPLAY 0.489362 (-2960 11175);
FORCEPROP 2 LASTPROP $XRERR UNIQUE?
J 0
(-3200 11175);
DISPLAY 0.638298 (-3200 11175);
PAINT MONO (-3200 11175);
DISPLAY INVISIBLE (-3200 11175);
WIRE 16 -1 (-3100 12775)(-1900 12775);
FORCEPROP 2 LAST SIG_NAME RST_CPU0_RESETL_N
J 0
(-2910 12785);
DISPLAY 0.489362 (-2910 12785);
WIRE 16 -1 (-3100 12675)(-1900 12675);
FORCEPROP 2 LAST SIG_NAME PWRGD_CPU0_PWROK
J 0
(-2910 12685);
DISPLAY 0.489362 (-2910 12685);
WIRE 16 -1 (-3100 12875)(-2300 12875);
FORCEPROP 2 LAST SIG_NAME CLK_CPU0_RTCCLK
J 0
(-2910 12885);
DISPLAY 0.489362 (-2910 12885);
WIRE 16 -1 (-5600 12525)(-6325 12525);
FORCEPROP 2 LAST SIG_NAME CPU0_PWR_BTN_N
J 0
(-6250 12535);
DISPLAY 0.489362 (-6250 12535);
WIRE 16 -1 (-3100 11625)(-2125 11625);
FORCEPROP 2 LAST SIG_NAME CLK_100M_CPU0_CLK02_R_DN
J 0
(-2960 11625);
DISPLAY 0.489362 (-2960 11625);
FORCEPROP 2 LASTPROP $XRERR UNIQUE?
J 0
(-3200 11625);
DISPLAY 0.638298 (-3200 11625);
PAINT MONO (-3200 11625);
DISPLAY INVISIBLE (-3200 11625);
WIRE 16 -1 (-3100 12225)(-2325 12225);
FORCEPROP 2 LAST SIG_NAME CPU0_NV_SAVE_N
J 0
(-2910 12235);
DISPLAY 0.489362 (-2910 12235);
WIRE 16 -1 (-1925 11625)(-650 11625);
FORCEPROP 2 LAST SIG_NAME CLK_100M_CPU0_CLK02_DN
J 0
(-1360 11635);
DISPLAY 0.489362 (-1360 11635);
WIRE 16 -1 (-1925 11825)(-650 11825);
FORCEPROP 2 LAST SIG_NAME CLK_100M_CPU0_CLK01_DP
J 0
(-1360 11835);
DISPLAY 0.489362 (-1360 11835);
WIRE 16 -1 (-1900 11475)(-650 11475);
FORCEPROP 2 LAST SIG_NAME CLK_100M_CPU0_CLK03_DN
J 0
(-1360 11485);
DISPLAY 0.489362 (-1360 11485);
WIRE 16 -1 (-1925 11775)(-650 11775);
FORCEPROP 2 LAST SIG_NAME CLK_100M_CPU0_CLK01_DN
J 0
(-1360 11785);
DISPLAY 0.489362 (-1360 11785);
WIRE 16 -1 (-5600 11925)(-6325 11925);
FORCEPROP 2 LAST SIG_NAME XTAL_CPU0_X32K_X2
J 0
(-6235 11935);
DISPLAY 0.489362 (-6235 11935);
WIRE 16 -1 (-5600 10625)(-6300 10625);
FORCEPROP 2 LAST SIG_NAME CPU0_SMERR_N
J 0
(-6160 10635);
DISPLAY 0.489362 (-6160 10635);
WIRE 16 -1 (-7875 12225)(-8475 12225);
FORCEPROP 2 LAST SIG_NAME RST_CPU0_SYS_N
J 0
(-8400 12235);
DISPLAY 0.489362 (-8400 12235);
WIRE 16 -1 (-8775 12825)(-7750 12825);
FORCEPROP 2 LAST SIG_NAME RST_CPU0_SYS_N
J 0
(-8310 12835);
DISPLAY 0.489362 (-8310 12835);
WIRE 16 -1 (-8775 12950)(-8775 12825);
WIRE 16 -1 (-8600 12875)(-7750 12875);
FORCEPROP 2 LAST SIG_NAME CPU0_PWR_BTN_N
J 0
(-8310 12885);
DISPLAY 0.489362 (-8310 12885);
WIRE 16 -1 (-8600 12950)(-8600 12875);
WIRE 16 -1 (-6325 12175)(-5600 12175);
FORCEPROP 2 LAST SIG_NAME XTAL_CPU0_X48M_X1
J 0
(-6235 12185);
DISPLAY 0.489362 (-6235 12185);
WIRE 16 -1 (-7175 12425)(-7125 12425);
FORCEPROP 2 LAST SIG_NAME RST_CPU0_RSMRST_N
J 0
(-7135 12435);
DISPLAY 0.489362 (-7135 12435);
WIRE 16 -1 (-7125 12425)(-5600 12425);
WIRE 16 -1 (-7125 12425)(-7125 12350);
WIRE 16 -1 (-6325 12325)(-5600 12325);
FORCEPROP 2 LAST SIG_NAME CPU0_PWR_GOOD
J 0
(-6235 12335);
DISPLAY 0.489362 (-6235 12335);
WIRE 16 -1 (-6325 11975)(-5600 11975);
FORCEPROP 2 LAST SIG_NAME XTAL_CPU0_X32K_X1
J 0
(-6235 11985);
DISPLAY 0.489362 (-6235 11985);
WIRE 16 -1 (-7000 11275)(-5600 11275);
FORCEPROP 2 LAST SIG_NAME I3C_0_SPD_DDRAF_CPU0_R_SDA
J 0
(-6400 11285);
DISPLAY 0.489362 (-6400 11285);
WIRE 16 -1 (-5600 11325)(-7000 11325);
FORCEPROP 2 LAST SIG_NAME I3C_0_SPD_DDRAF_CPU0_R_SCL
J 0
(-6400 11335);
DISPLAY 0.489362 (-6400 11335);
WIRE 16 -1 (-1700 12975)(-900 12975);
FORCEPROP 2 LAST SIG_NAME CLK_100M_REF_IN_DN
J 0
(-1535 12985);
DISPLAY 0.489362 (-1535 12985);
WIRE 16 -1 (-3100 12975)(-1900 12975);
FORCEPROP 2 LAST SIG_NAME CLK_100M_REF_OUT_DN
J 0
(-2910 12985);
DISPLAY 0.489362 (-2910 12985);
FORCEPROP 2 LASTPROP $XRERR UNIQUE?
J 0
(-3150 12985);
DISPLAY 0.638298 (-3150 12985);
PAINT MONO (-3150 12985);
DISPLAY INVISIBLE (-3150 12985);
WIRE 16 -1 (-1700 13025)(-900 13025);
FORCEPROP 2 LAST SIG_NAME CLK_100M_REF_IN_DP
J 0
(-1535 13035);
DISPLAY 0.489362 (-1535 13035);
WIRE 16 -1 (-3100 13025)(-1900 13025);
FORCEPROP 2 LAST SIG_NAME CLK_100M_REF_OUT_DP
J 0
(-2910 13035);
DISPLAY 0.489362 (-2910 13035);
FORCEPROP 2 LASTPROP $XRERR UNIQUE?
J 0
(-3150 13035);
DISPLAY 0.638298 (-3150 13035);
PAINT MONO (-3150 13035);
DISPLAY INVISIBLE (-3150 13035);
WIRE 16 -1 (-6750 11075)(-5600 11075);
FORCEPROP 2 LAST SIG_NAME SMB_CPU0_2_R_SDA
J 0
(-6400 11085);
DISPLAY 0.489362 (-6400 11085);
FORCEPROP 2 LASTPROP $XRERR UNIQUE?
J 0
(-6640 11085);
DISPLAY 0.638298 (-6640 11085);
PAINT MONO (-6640 11085);
DISPLAY INVISIBLE (-6640 11085);
WIRE 16 -1 (-6750 11025)(-5600 11025);
FORCEPROP 2 LAST SIG_NAME SMB_CPU0_3_R_SCL
J 0
(-6400 11035);
DISPLAY 0.489362 (-6400 11035);
FORCEPROP 2 LASTPROP $XRERR UNIQUE?
J 0
(-6640 11035);
DISPLAY 0.638298 (-6640 11035);
PAINT MONO (-6640 11035);
DISPLAY INVISIBLE (-6640 11035);
WIRE 16 -1 (-6750 10975)(-5600 10975);
FORCEPROP 2 LAST SIG_NAME SMB_CPU0_3_R_SDA
J 0
(-6400 10985);
DISPLAY 0.489362 (-6400 10985);
FORCEPROP 2 LASTPROP $XRERR UNIQUE?
J 0
(-6640 10985);
DISPLAY 0.638298 (-6640 10985);
PAINT MONO (-6640 10985);
DISPLAY INVISIBLE (-6640 10985);
WIRE 16 -1 (-6400 12675)(-5600 12675);
FORCEPROP 2 LAST SIG_NAME CPU0_SLP_S5_N
J 0
(-6250 12685);
DISPLAY 0.489362 (-6250 12685);
FORCEPROP 2 LASTPROP $XR0 28 
J 0
(-6520 12685);
DISPLAY 0.638298 (-6520 12685);
PAINT MONO (-6520 12685);
WIRE 16 -1 (-7175 12675)(-6600 12675);
FORCEPROP 2 LAST SIG_NAME FM_CPU0_SLP_S5_N
J 0
(-7135 12700);
DISPLAY 0.489362 (-7135 12700);
WIRE 16 -1 (-5600 12625)(-6400 12625);
FORCEPROP 2 LAST SIG_NAME CPU0_SLP_S3_N
J 0
(-6250 12635);
DISPLAY 0.489362 (-6250 12635);
FORCEPROP 2 LASTPROP $XR0 28 
J 0
(-6520 12635);
DISPLAY 0.638298 (-6520 12635);
PAINT MONO (-6520 12635);
WIRE 16 -1 (-7175 12625)(-6600 12625);
FORCEPROP 2 LAST SIG_NAME FM_CPU0_SLP_S3_N
J 0
(-7135 12650);
DISPLAY 0.489362 (-7135 12650);
WIRE 16 -1 (-1475 12525)(-2075 12525);
FORCEPROP 2 LAST SIG_NAME CPU1_PWR_GD_IN
J 0
(-1935 12535);
DISPLAY 0.489362 (-1935 12535);
WIRE 16 -1 (-3100 12525)(-2275 12525);
FORCEPROP 2 LAST SIG_NAME CPU0_PWR_GD_OUT
J 0
(-2910 12535);
DISPLAY 0.489362 (-2910 12535);
FORCEPROP 2 LASTPROP $XR0 28 
J 0
(-3185 12535);
DISPLAY 0.638298 (-3185 12535);
PAINT MONO (-3185 12535);
WIRE 16 -1 (-6750 11125)(-5600 11125);
FORCEPROP 2 LAST SIG_NAME SMB_CPU0_2_R_SCL
J 0
(-6400 11135);
DISPLAY 0.489362 (-6400 11135);
FORCEPROP 2 LASTPROP $XRERR UNIQUE?
J 0
(-6640 11135);
DISPLAY 0.638298 (-6640 11135);
PAINT MONO (-6640 11135);
DISPLAY INVISIBLE (-6640 11135);
WIRE 16 -1 (-3100 12325)(-2325 12325);
FORCEPROP 2 LAST SIG_NAME CPU0_FORCE_SELFREFRESH
J 0
(-2910 12335);
DISPLAY 0.489362 (-2910 12335);
WIRE 16 -1 (-8575 9550)(-8575 9475);
WIRE 16 -1 (-8575 9475)(-7725 9475);
FORCEPROP 2 LAST SIG_NAME I3C_0_SPD_DDRAF_CPU0_R_SCL
J 2
(-7785 9485);
DISPLAY 0.489362 (-7785 9485);
WIRE 16 -1 (-8750 9425)(-7725 9425);
FORCEPROP 2 LAST SIG_NAME I3C_0_SPD_DDRAF_CPU0_R_SDA
J 2
(-7785 9435);
DISPLAY 0.489362 (-7785 9435);
WIRE 16 -1 (-8750 9550)(-8750 9425);
WIRE 16 -1 (-7725 9375)(-8925 9375);
FORCEPROP 2 LAST SIG_NAME I3C_1_SPD_DDRGL_CPU0_R_SCL
J 2
(-7785 9385);
DISPLAY 0.489362 (-7785 9385);
WIRE 16 -1 (-8925 9550)(-8925 9375);
WIRE 16 -1 (-6475 9925)(-7250 9925);
FORCEPROP 2 LAST SIG_NAME FM_BIOS_POST_CMPLT_N
J 0
(-7225 9935);
DISPLAY 0.489362 (-7225 9935);
WIRE 16 -1 (-7000 11175)(-5600 11175);
FORCEPROP 2 LAST SIG_NAME I3C_1_SPD_DDRGL_CPU0_R_SDA
J 0
(-6400 11185);
DISPLAY 0.489362 (-6400 11185);
WIRE 16 -1 (-5600 10775)(-6750 10775);
FORCEPROP 2 LAST SIG_NAME SMB_CPU_5_R_SDA
J 0
(-6400 10785);
DISPLAY 0.489362 (-6400 10785);
FORCEPROP 2 LASTPROP $XRERR UNIQUE?
J 0
(-6640 10785);
DISPLAY 0.638298 (-6640 10785);
PAINT MONO (-6640 10785);
DISPLAY INVISIBLE (-6640 10785);
WIRE 16 -1 (-5600 12125)(-6325 12125);
FORCEPROP 2 LAST SIG_NAME XTAL_CPU0_X48M_X2
J 0
(-6235 12135);
DISPLAY 0.489362 (-6235 12135);
WIRE 16 -1 (-5600 10325)(-6275 10325);
FORCEPROP 2 LAST SIG_NAME FM_PASSWORD_CLEAR_R_N
J 0
(-6200 10335);
DISPLAY 0.489362 (-6200 10335);
FORCEPROP 2 LASTPROP $XRERR UNIQUE?
J 0
(-6440 10335);
DISPLAY 0.638298 (-6440 10335);
PAINT MONO (-6440 10335);
DISPLAY INVISIBLE (-6440 10335);
WIRE 16 -1 (-5600 10125)(-7250 10125);
FORCEPROP 2 LAST SIG_NAME IRQ_TPM_SPI_R_N
J 0
(-7225 10135);
DISPLAY 0.489362 (-7225 10135);
WIRE 16 -1 (-7250 10075)(-5600 10075);
FORCEPROP 2 LAST SIG_NAME FM_BOARD_SKU_ID0
J 0
(-7225 10085);
DISPLAY 0.489362 (-7225 10085);
WIRE 16 -1 (-8700 8975)(-7875 8975);
FORCEPROP 2 LAST SIG_NAME BOOT_RDY_H
J 0
(-8585 8985);
DISPLAY 0.489362 (-8585 8985);
WIRE 16 -1 (-7875 8925)(-8700 8925);
FORCEPROP 2 LAST SIG_NAME CPU0_FORCE_SELFREFRESH
J 0
(-8710 8935);
DISPLAY 0.489362 (-8710 8935);
WIRE 16 -1 (-7725 9325)(-9100 9325);
FORCEPROP 2 LAST SIG_NAME I3C_1_SPD_DDRGL_CPU0_R_SDA
J 2
(-7785 9335);
DISPLAY 0.489362 (-7785 9335);
WIRE 16 -1 (-9100 9550)(-9100 9325);
WIRE 16 -1 (-1900 10775)(-650 10775);
FORCEPROP 2 LAST SIG_NAME CLK_100M_CPU0_CLK13_DP
J 0
(-1385 10785);
DISPLAY 0.553191 (-1385 10785);
WIRE 16 -1 (-3450 8450)(-3900 8450);
WIRE 16 -1 (-3900 8750)(-3900 8450);
WIRE 16 -1 (-3900 8450)(-3900 8150);
WIRE 16 -1 (-3450 8750)(-3900 8750);
WIRE 16 -1 (-3900 8750)(-3900 9175);
WIRE 16 -1 (-3900 9175)(-2325 9175);
FORCEPROP 2 LAST SIG_NAME XTAL_CPU0_X32K_X1
J 0
(-2785 9185);
DISPLAY 0.489362 (-2785 9185);
WIRE 16 -1 (-2800 8750)(-2800 9125);
WIRE 16 -1 (-2800 8750)(-2800 8450);
WIRE 16 -1 (-3250 8750)(-2800 8750);
WIRE 16 -1 (-2800 9125)(-2325 9125);
FORCEPROP 2 LAST SIG_NAME XTAL_CPU0_X32K_X2
J 0
(-2785 9135);
DISPLAY 0.489362 (-2785 9135);
WIRE 16 -1 (-3250 8450)(-2800 8450);
WIRE 16 -1 (-2800 8450)(-2800 8175);
WIRE 16 -1 (-6950 11025)(-8175 11025);
FORCEPROP 2 LAST SIG_NAME SMB_CPU0_3_SCL
J 0
(-7725 11035);
DISPLAY 0.489362 (-7725 11035);
FORCEPROP 2 LASTPROP $XRERR UNIQUE?
J 0
(-7965 11035);
DISPLAY 0.638298 (-7965 11035);
PAINT MONO (-7965 11035);
DISPLAY INVISIBLE (-7965 11035);
WIRE 16 -1 (-6750 10875)(-5600 10875);
FORCEPROP 2 LAST SIG_NAME SMB_CPU0_4_R_SDA
J 0
(-6400 10885);
DISPLAY 0.489362 (-6400 10885);
FORCEPROP 2 LASTPROP $XRERR UNIQUE?
J 0
(-6640 10885);
DISPLAY 0.638298 (-6640 10885);
PAINT MONO (-6640 10885);
DISPLAY INVISIBLE (-6640 10885);
WIRE 16 -1 (-6750 10925)(-5600 10925);
FORCEPROP 2 LAST SIG_NAME SMB_CPU0_4_R_SCL
J 0
(-6400 10935);
DISPLAY 0.489362 (-6400 10935);
FORCEPROP 2 LASTPROP $XRERR UNIQUE?
J 0
(-6640 10935);
DISPLAY 0.638298 (-6640 10935);
PAINT MONO (-6640 10935);
DISPLAY INVISIBLE (-6640 10935);
WIRE 16 -1 (-5600 11225)(-7000 11225);
FORCEPROP 2 LAST SIG_NAME I3C_1_SPD_DDRGL_CPU0_R_SCL
J 0
(-6400 11235);
DISPLAY 0.489362 (-6400 11235);
WIRE 16 -1 (-6950 11125)(-8175 11125);
FORCEPROP 2 LAST SIG_NAME SMB_CPU0_2_SCL
J 0
(-7725 11135);
DISPLAY 0.489362 (-7725 11135);
FORCEPROP 2 LASTPROP $XRERR UNIQUE?
J 0
(-7965 11135);
DISPLAY 0.638298 (-7965 11135);
PAINT MONO (-7965 11135);
DISPLAY INVISIBLE (-7965 11135);
WIRE 16 -1 (-6950 10975)(-8175 10975);
FORCEPROP 2 LAST SIG_NAME SMB_CPU0_3_SDA
J 0
(-7725 10985);
DISPLAY 0.489362 (-7725 10985);
FORCEPROP 2 LASTPROP $XRERR UNIQUE?
J 0
(-7965 10985);
DISPLAY 0.638298 (-7965 10985);
PAINT MONO (-7965 10985);
DISPLAY INVISIBLE (-7965 10985);
WIRE 16 -1 (-6950 10925)(-7850 10925);
FORCEPROP 2 LAST SIG_NAME SMB_CPU0_4_SCL
J 0
(-7725 10935);
DISPLAY 0.489362 (-7725 10935);
WIRE 16 -1 (-6950 10875)(-7850 10875);
FORCEPROP 2 LAST SIG_NAME SMB_CPU0_4_SDA
J 0
(-7725 10885);
DISPLAY 0.489362 (-7725 10885);
WIRE 16 -1 (-7850 10775)(-6950 10775);
FORCEPROP 2 LAST SIG_NAME SMB_CPU_5_SDA
J 0
(-7725 10785);
DISPLAY 0.489362 (-7725 10785);
WIRE 16 -1 (-7250 10325)(-6475 10325);
FORCEPROP 2 LAST SIG_NAME FM_PASSWORD_CLEAR_N
J 0
(-7225 10335);
DISPLAY 0.489362 (-7225 10335);
WIRE 16 -1 (-5600 10225)(-7250 10225);
FORCEPROP 2 LAST SIG_NAME IRQ_BMC_SMI_N
J 0
(-7225 10235);
DISPLAY 0.489362 (-7225 10235);
WIRE 16 -1 (-5600 10275)(-7250 10275);
FORCEPROP 2 LAST SIG_NAME FM_SMM_CRASHDUMP
J 0
(-7225 10285);
DISPLAY 0.553191 (-7225 10285);
WIRE 16 -1 (-7250 10375)(-5600 10375);
FORCEPROP 2 LAST SIG_NAME CPU0_SPD_HOST_CTRL_N
J 0
(-7225 10385);
DISPLAY 0.489362 (-7225 10385);
WIRE 16 -1 (-6950 11075)(-8175 11075);
FORCEPROP 2 LAST SIG_NAME SMB_CPU0_2_SDA
J 0
(-7725 11085);
DISPLAY 0.489362 (-7725 11085);
FORCEPROP 2 LASTPROP $XRERR UNIQUE?
J 0
(-7965 11085);
DISPLAY 0.638298 (-7965 11085);
PAINT MONO (-7965 11085);
DISPLAY INVISIBLE (-7965 11085);
DOT 1 (-6925 7900);
DOT 1 (-7425 8975);
DOT 1 (-7425 8275);
DOT 1 (-7425 8675);
DOT 1 (-6925 7400);
DOT 1 (-7425 8425);
DOT 1 (-7625 7600);
DOT 1 (-7625 7900);
DOT 1 (-4950 8125);
DOT 1 (-7425 8925);
DOT 1 (-4950 8725);
DOT 1 (-6225 8725);
DOT 1 (-7425 8375);
DOT 1 (-7425 8325);
DOT 1 (-3900 8750);
DOT 1 (-7075 7900);
DOT 1 (-7075 7450);
DOT 1 (-6775 7350);
DOT 1 (-7425 8225);
DOT 1 (-7225 7900);
DOT 1 (-7400 7900);
DOT 1 (-7225 7500);
DOT 1 (-7400 7550);
DOT 1 (-7900 7650);
DOT 1 (-8600 13200);
DOT 1 (-9125 12125);
DOT 1 (-8575 9800);
DOT 1 (-8750 9800);
DOT 1 (-8925 9800);
DOT 1 (-7125 12425);
DOT 1 (-8475 11025);
DOT 1 (-8475 11125);
DOT 1 (-8475 11075);
DOT 1 (-2800 8750);
DOT 1 (-9125 12225);
DOT 1 (-7425 8725);
DOT 1 (-7425 8775);
DOT 1 (-3900 8450);
DOT 1 (-2800 8450);
DOT 1 (-6225 8125);
FORCENOTE
$CDS_IMAGE|clipboard_2_8.jpg|2130|975
(-1350 8525) 0;
DISPLAY LEFT (-1350 8525);
QUIT
